G04 ================== begin FILE IDENTIFICATION RECORD ==================*
G04 Layout Name:  13130-1b.brd*
G04 Film Name:    L7VCC*
G04 File Format:  Gerber RS274X*
G04 File Origin:  Cadence Allegro 16.5-S037*
G04 Origin Date:  Thu Nov 13 17:27:07 2014*
G04 *
G04 Layer:  VIA CLASS/L7VCC*
G04 Layer:  PIN/L7VCC*
G04 Layer:  PACKAGE GEOMETRY/PWRVCC*
G04 Layer:  ETCH/L7VCC*
G04 Layer:  DRAWING FORMAT/LAYER_PCB_STORY*
G04 Layer:  DRAWING FORMAT/LAYER_L7VCC*
G04 *
G04 Offset:    (0.00 0.00)*
G04 Mirror:    No*
G04 Mode:      Negative*
G04 Rotation:  0*
G04 FullContactRelief:  No*
G04 UndefLineWidth:     6.00*
G04 ================== end FILE IDENTIFICATION RECORD ====================*
%FSLAX35Y35*MOIN*%
%IR0*IPPOS*OFA0.00000B0.00000*MIA0B0*SFA1.00000B1.00000*%
%ADD15C,.03*%
%ADD20C,.032*%
%ADD18C,.072*%
%ADD13C,.036*%
%ADD24C,.028*%
%ADD22C,.091*%
%ADD17C,.093*%
%ADD19C,.068*%
%AMMACRO23*
4,1,15,.00398,.00044,
.003999,.000208,
.004004,-.000025,
.003996,-.000258,
.00398,-.00044,
.00483,-.00129,
.004897,-.001007,
.004947,-.000721,
.004981,-.000432,
.004997,-.000141,
.004997,.000149,
.00498,.00044,
.004946,.000729,
.004895,.001015,
.00483,.00129,
.00398,.00044,
45.*
4,1,15,.00044,-.00398,
.000208,-.003999,
-.000025,-.004004,
-.000258,-.003996,
-.00044,-.00398,
-.00129,-.00483,
-.001007,-.004897,
-.000721,-.004947,
-.000432,-.004981,
-.000141,-.004997,
.000149,-.004997,
.00044,-.00498,
.000729,-.004946,
.001015,-.004895,
.00129,-.00483,
.00044,-.00398,
45.*
4,1,15,-.00398,-.00044,
-.003999,-.000208,
-.004004,.000025,
-.003996,.000258,
-.00398,.00044,
-.00483,.00129,
-.004897,.001007,
-.004947,.000721,
-.004981,.000432,
-.004997,.000141,
-.004997,-.000149,
-.00498,-.00044,
-.004946,-.000729,
-.004895,-.001015,
-.00483,-.00129,
-.00398,-.00044,
45.*
4,1,15,-.00044,.00398,
-.000208,.003999,
.000025,.004004,
.000258,.003996,
.00044,.00398,
.00129,.00483,
.001007,.004897,
.000721,.004947,
.000432,.004981,
.000141,.004997,
-.000149,.004997,
-.00044,.00498,
-.000729,.004946,
-.001015,.004895,
-.00129,.00483,
-.00044,.00398,
45.*
%
%ADD23MACRO23*%
%AMMACRO14*
4,1,15,.00398,.00044,
.003999,.000208,
.004004,-.000025,
.003996,-.000258,
.00398,-.00044,
.00483,-.00129,
.004897,-.001007,
.004947,-.000721,
.004981,-.000432,
.004997,-.000141,
.004997,.000149,
.00498,.00044,
.004946,.000729,
.004895,.001015,
.00483,.00129,
.00398,.00044,
90.*
4,1,15,.00044,-.00398,
.000208,-.003999,
-.000025,-.004004,
-.000258,-.003996,
-.00044,-.00398,
-.00129,-.00483,
-.001007,-.004897,
-.000721,-.004947,
-.000432,-.004981,
-.000141,-.004997,
.000149,-.004997,
.00044,-.00498,
.000729,-.004946,
.001015,-.004895,
.00129,-.00483,
.00044,-.00398,
90.*
4,1,15,-.00398,-.00044,
-.003999,-.000208,
-.004004,.000025,
-.003996,.000258,
-.00398,.00044,
-.00483,.00129,
-.004897,.001007,
-.004947,.000721,
-.004981,.000432,
-.004997,.000141,
-.004997,-.000149,
-.00498,-.00044,
-.004946,-.000729,
-.004895,-.001015,
-.00483,-.00129,
-.00398,-.00044,
90.*
4,1,15,-.00044,.00398,
-.000208,.003999,
.000025,.004004,
.000258,.003996,
.00044,.00398,
.00129,.00483,
.001007,.004897,
.000721,.004947,
.000432,.004981,
.000141,.004997,
-.000149,.004997,
-.00044,.00498,
-.000729,.004946,
-.001015,.004895,
-.00129,.00483,
-.00044,.00398,
90.*
%
%ADD14MACRO14*%
%AMMACRO12*
4,1,15,.00398,.00044,
.003999,.000208,
.004004,-.000025,
.003996,-.000258,
.00398,-.00044,
.00483,-.00129,
.004897,-.001007,
.004947,-.000721,
.004981,-.000432,
.004997,-.000141,
.004997,.000149,
.00498,.00044,
.004946,.000729,
.004895,.001015,
.00483,.00129,
.00398,.00044,
0.0*
4,1,15,.00044,-.00398,
.000208,-.003999,
-.000025,-.004004,
-.000258,-.003996,
-.00044,-.00398,
-.00129,-.00483,
-.001007,-.004897,
-.000721,-.004947,
-.000432,-.004981,
-.000141,-.004997,
.000149,-.004997,
.00044,-.00498,
.000729,-.004946,
.001015,-.004895,
.00129,-.00483,
.00044,-.00398,
0.0*
4,1,15,-.00398,-.00044,
-.003999,-.000208,
-.004004,.000025,
-.003996,.000258,
-.00398,.00044,
-.00483,.00129,
-.004897,.001007,
-.004947,.000721,
-.004981,.000432,
-.004997,.000141,
-.004997,-.000149,
-.00498,-.00044,
-.004946,-.000729,
-.004895,-.001015,
-.00483,-.00129,
-.00398,-.00044,
0.0*
4,1,15,-.00044,.00398,
-.000208,.003999,
.000025,.004004,
.000258,.003996,
.00044,.00398,
.00129,.00483,
.001007,.004897,
.000721,.004947,
.000432,.004981,
.000141,.004997,
-.000149,.004997,
-.00044,.00498,
-.000729,.004946,
-.001015,.004895,
-.00129,.00483,
-.00044,.00398,
0.0*
%
%ADD12MACRO12*%
%ADD29O,.217X.154*%
%ADD11C,.114*%
%ADD16C,.154*%
%ADD21C,.147*%
%ADD10C,.168*%
%AMMACRO30*
4,1,15,.00398,.00044,
.003999,.000208,
.004004,-.000025,
.003996,-.000258,
.00398,-.00044,
.00483,-.00129,
.004897,-.001007,
.004947,-.000721,
.004981,-.000432,
.004997,-.000141,
.004997,.000149,
.00498,.00044,
.004946,.000729,
.004895,.001015,
.00483,.00129,
.00398,.00044,
225.*
4,1,15,.00044,-.00398,
.000208,-.003999,
-.000025,-.004004,
-.000258,-.003996,
-.00044,-.00398,
-.00129,-.00483,
-.001007,-.004897,
-.000721,-.004947,
-.000432,-.004981,
-.000141,-.004997,
.000149,-.004997,
.00044,-.00498,
.000729,-.004946,
.001015,-.004895,
.00129,-.00483,
.00044,-.00398,
225.*
4,1,15,-.00398,-.00044,
-.003999,-.000208,
-.004004,.000025,
-.003996,.000258,
-.00398,.00044,
-.00483,.00129,
-.004897,.001007,
-.004947,.000721,
-.004981,.000432,
-.004997,.000141,
-.004997,-.000149,
-.00498,-.00044,
-.004946,-.000729,
-.004895,-.001015,
-.00483,-.00129,
-.00398,-.00044,
225.*
4,1,15,-.00044,.00398,
-.000208,.003999,
.000025,.004004,
.000258,.003996,
.00044,.00398,
.00129,.00483,
.001007,.004897,
.000721,.004947,
.000432,.004981,
.000141,.004997,
-.000149,.004997,
-.00044,.00498,
-.000729,.004946,
-.001015,.004895,
-.00129,.00483,
-.00044,.00398,
225.*
%
%ADD30MACRO30*%
%AMMACRO28*
4,1,15,.00398,.00044,
.003999,.000208,
.004004,-.000025,
.003996,-.000258,
.00398,-.00044,
.00483,-.00129,
.004897,-.001007,
.004947,-.000721,
.004981,-.000432,
.004997,-.000141,
.004997,.000149,
.00498,.00044,
.004946,.000729,
.004895,.001015,
.00483,.00129,
.00398,.00044,
315.*
4,1,15,.00044,-.00398,
.000208,-.003999,
-.000025,-.004004,
-.000258,-.003996,
-.00044,-.00398,
-.00129,-.00483,
-.001007,-.004897,
-.000721,-.004947,
-.000432,-.004981,
-.000141,-.004997,
.000149,-.004997,
.00044,-.00498,
.000729,-.004946,
.001015,-.004895,
.00129,-.00483,
.00044,-.00398,
315.*
4,1,15,-.00398,-.00044,
-.003999,-.000208,
-.004004,.000025,
-.003996,.000258,
-.00398,.00044,
-.00483,.00129,
-.004897,.001007,
-.004947,.000721,
-.004981,.000432,
-.004997,.000141,
-.004997,-.000149,
-.00498,-.00044,
-.004946,-.000729,
-.004895,-.001015,
-.00483,-.00129,
-.00398,-.00044,
315.*
4,1,15,-.00044,.00398,
-.000208,.003999,
.000025,.004004,
.000258,.003996,
.00044,.00398,
.00129,.00483,
.001007,.004897,
.000721,.004947,
.000432,.004981,
.000141,.004997,
-.000149,.004997,
-.00044,.00498,
-.000729,.004946,
-.001015,.004895,
-.00129,.00483,
-.00044,.00398,
315.*
%
%ADD28MACRO28*%
%AMMACRO27*
4,1,15,.00398,.00044,
.003999,.000208,
.004004,-.000025,
.003996,-.000258,
.00398,-.00044,
.00483,-.00129,
.004897,-.001007,
.004947,-.000721,
.004981,-.000432,
.004997,-.000141,
.004997,.000149,
.00498,.00044,
.004946,.000729,
.004895,.001015,
.00483,.00129,
.00398,.00044,
180.*
4,1,15,.00044,-.00398,
.000208,-.003999,
-.000025,-.004004,
-.000258,-.003996,
-.00044,-.00398,
-.00129,-.00483,
-.001007,-.004897,
-.000721,-.004947,
-.000432,-.004981,
-.000141,-.004997,
.000149,-.004997,
.00044,-.00498,
.000729,-.004946,
.001015,-.004895,
.00129,-.00483,
.00044,-.00398,
180.*
4,1,15,-.00398,-.00044,
-.003999,-.000208,
-.004004,.000025,
-.003996,.000258,
-.00398,.00044,
-.00483,.00129,
-.004897,.001007,
-.004947,.000721,
-.004981,.000432,
-.004997,.000141,
-.004997,-.000149,
-.00498,-.00044,
-.004946,-.000729,
-.004895,-.001015,
-.00483,-.00129,
-.00398,-.00044,
180.*
4,1,15,-.00044,.00398,
-.000208,.003999,
.000025,.004004,
.000258,.003996,
.00044,.00398,
.00129,.00483,
.001007,.004897,
.000721,.004947,
.000432,.004981,
.000141,.004997,
-.000149,.004997,
-.00044,.00498,
-.000729,.004946,
-.001015,.004895,
-.00129,.00483,
-.00044,.00398,
180.*
%
%ADD27MACRO27*%
%AMMACRO26*
4,1,15,.00398,.00044,
.003999,.000208,
.004004,-.000025,
.003996,-.000258,
.00398,-.00044,
.00483,-.00129,
.004897,-.001007,
.004947,-.000721,
.004981,-.000432,
.004997,-.000141,
.004997,.000149,
.00498,.00044,
.004946,.000729,
.004895,.001015,
.00483,.00129,
.00398,.00044,
270.*
4,1,15,.00044,-.00398,
.000208,-.003999,
-.000025,-.004004,
-.000258,-.003996,
-.00044,-.00398,
-.00129,-.00483,
-.001007,-.004897,
-.000721,-.004947,
-.000432,-.004981,
-.000141,-.004997,
.000149,-.004997,
.00044,-.00498,
.000729,-.004946,
.001015,-.004895,
.00129,-.00483,
.00044,-.00398,
270.*
4,1,15,-.00398,-.00044,
-.003999,-.000208,
-.004004,.000025,
-.003996,.000258,
-.00398,.00044,
-.00483,.00129,
-.004897,.001007,
-.004947,.000721,
-.004981,.000432,
-.004997,.000141,
-.004997,-.000149,
-.00498,-.00044,
-.004946,-.000729,
-.004895,-.001015,
-.00483,-.00129,
-.00398,-.00044,
270.*
4,1,15,-.00044,.00398,
-.000208,.003999,
.000025,.004004,
.000258,.003996,
.00044,.00398,
.00129,.00483,
.001007,.004897,
.000721,.004947,
.000432,.004981,
.000141,.004997,
-.000149,.004997,
-.00044,.00498,
-.000729,.004946,
-.001015,.004895,
-.00129,.00483,
-.00044,.00398,
270.*
%
%ADD26MACRO26*%
%AMMACRO25*
4,1,15,.00398,.00044,
.003999,.000208,
.004004,-.000025,
.003996,-.000258,
.00398,-.00044,
.00483,-.00129,
.004897,-.001007,
.004947,-.000721,
.004981,-.000432,
.004997,-.000141,
.004997,.000149,
.00498,.00044,
.004946,.000729,
.004895,.001015,
.00483,.00129,
.00398,.00044,
135.*
4,1,15,.00044,-.00398,
.000208,-.003999,
-.000025,-.004004,
-.000258,-.003996,
-.00044,-.00398,
-.00129,-.00483,
-.001007,-.004897,
-.000721,-.004947,
-.000432,-.004981,
-.000141,-.004997,
.000149,-.004997,
.00044,-.00498,
.000729,-.004946,
.001015,-.004895,
.00129,-.00483,
.00044,-.00398,
135.*
4,1,15,-.00398,-.00044,
-.003999,-.000208,
-.004004,.000025,
-.003996,.000258,
-.00398,.00044,
-.00483,.00129,
-.004897,.001007,
-.004947,.000721,
-.004981,.000432,
-.004997,.000141,
-.004997,-.000149,
-.00498,-.00044,
-.004946,-.000729,
-.004895,-.001015,
-.00483,-.00129,
-.00398,-.00044,
135.*
4,1,15,-.00044,.00398,
-.000208,.003999,
.000025,.004004,
.000258,.003996,
.00044,.00398,
.00129,.00483,
.001007,.004897,
.000721,.004947,
.000432,.004981,
.000141,.004997,
-.000149,.004997,
-.00044,.00498,
-.000729,.004946,
-.001015,.004895,
-.00129,.00483,
-.00044,.00398,
135.*
%
%ADD25MACRO25*%
%ADD31C,.02*%
%ADD32C,.006*%
%ADD41C,.03004*%
%ADD38C,.06404*%
%ADD37C,.06804*%
%ADD39C,.08704*%
%ADD36C,.08904*%
%ADD40C,.09176*%
%ADD33O,.21302X.15002*%
%ADD34C,.11004*%
%ADD35C,.15004*%
G75*
%LPD*%
G75*
G36*
G01X-6000Y-6000D02*
X832773D01*
Y296551D01*
X-6000D01*
Y-6000D01*
G37*
%LPC*%
G75*
G36*
G01X417323Y3004D02*
G02X416390Y3937I0J933D01*
G01Y42126D01*
G03X409449Y49067I-6941J0D01*
G01X393701D01*
G03X386760Y42126I0J-6941D01*
G01Y20648D01*
X348673D01*
Y39961D01*
G03X335185I-6744J0D01*
G01Y20648D01*
X60878D01*
Y53937D01*
G03X53937Y60878I-6941J0D01*
G01X3937D01*
G02X3004Y61811I0J933D01*
G01Y286614D01*
G02X3937Y287547I933J0D01*
G01X193177D01*
G02X193514Y286932I0J-400D01*
G03X206880I6683J-4255D01*
G02X207217Y287547I337J215D01*
G01X291579D01*
G02X291917Y286933I0J-400D01*
G03X305327I6705J-4256D01*
G02X305665Y287547I338J214D01*
G01X822835D01*
G02X823768Y286614I0J-933D01*
G01Y3937D01*
G02X822835Y3004I-933J0D01*
G01X417323D01*
G37*
%LPD*%
G75*
G36*
G01X9110Y260712D02*
G02X6090Y260713I-1510J1D01*
G01Y264483D01*
G02X9110I1510J0D01*
G01Y260712D01*
G37*
G36*
G01X15100Y254750D02*
G02X12080Y254751I-1510J1D01*
G01Y258521D01*
G02X15100I1510J0D01*
G01Y254750D01*
G37*
G36*
G01X39410Y253999D02*
G02X36390Y254000I-1510J1D01*
G01Y257500D01*
G02X39410I1510J0D01*
G01Y253999D01*
G37*
G36*
G01X9110Y248902D02*
G02X6090I-1510J0D01*
G01Y252673D01*
G02X9110Y252672I1510J-1D01*
G01Y248902D01*
G37*
G36*
G01X36397Y246861D02*
X36381Y247035D01*
X36481Y250542D01*
X36489Y250550D01*
X36495Y250624D01*
G02X39503Y250639I1505J-123D01*
G01X39519Y250465D01*
X39419Y246957D01*
X39394Y246785D01*
G02X36397Y246861I-1494J216D01*
G37*
G36*
G01X400528Y242794D02*
G02X398368Y244905I-1090J1045D01*
G01X400768Y247314D01*
G02X402908Y245182I1070J-1066D01*
G01X400529Y242795D01*
X400528Y242794D01*
G37*
G36*
G01X15100Y242939D02*
G02X12080Y242940I-1510J1D01*
G01Y246710D01*
G02X15100I1510J0D01*
G01Y242939D01*
G37*
G36*
G01X39410Y239999D02*
G02X36390Y240000I-1510J1D01*
G01Y243500D01*
G02X39410I1510J0D01*
G01Y239999D01*
G37*
G36*
G01X390616Y239712D02*
X390725Y239846D01*
X393170Y242218D01*
X393181D01*
X393237Y242267D01*
G02X395280Y240044I991J-1139D01*
G01X395137Y239905D01*
X395143Y239898D01*
X392844Y237667D01*
X392707Y237562D01*
G02X390616Y239712I-919J1198D01*
G37*
G36*
G01X9110Y237090D02*
G02X6090Y237091I-1510J1D01*
G01Y240861D01*
G02X9110I1510J0D01*
G01Y237090D01*
G37*
G36*
G01X36397Y232861D02*
X36381Y233035D01*
X36481Y236542D01*
X36489Y236550D01*
X36495Y236624D01*
G02X39503Y236639I1505J-123D01*
G01X39519Y236465D01*
X39419Y232957D01*
X39394Y232785D01*
G02X36397Y232861I-1494J216D01*
G37*
G36*
G01X14600Y231129D02*
G02X11580I-1510J0D01*
G01Y234900D01*
G02X14600Y234899I1510J-1D01*
G01Y231129D01*
G37*
G36*
G01X39410Y225999D02*
G02X36390Y226000I-1510J1D01*
G01Y229500D01*
G02X39410I1510J0D01*
G01Y225999D01*
G37*
G36*
G01Y218999D02*
G02X36390Y219000I-1510J1D01*
G01Y222500D01*
G02X39410I1510J0D01*
G01Y218999D01*
G37*
G36*
G01X329534Y219215D02*
G02X327485Y217426I-1025J-895D01*
G01X325999Y219130D01*
G02X328049Y220918I1025J894D01*
G01X329534Y219215D01*
G37*
G36*
G01X359255Y215107D02*
X359109Y215175D01*
X357235Y216357D01*
Y216365D01*
X357154Y216425D01*
G02X358692Y218666I812J1091D01*
G01X358861Y218559D01*
X358866Y218567D01*
X360570Y217492D01*
X360694Y217389D01*
G02X359255Y215107I-867J-1048D01*
G37*
G36*
G01X338701Y215752D02*
G02X335981Y215710I-1360J-21D01*
G01X335947Y217939D01*
G02X338667Y217982I1360J22D01*
G01X338701Y215752D01*
G37*
G36*
G01X344602Y213717D02*
G02X341882Y213663I-1360J-27D01*
G01X341838Y215882D01*
G02X344558Y215937I1360J27D01*
G01X344602Y213717D01*
G37*
G36*
G01X333018Y212687D02*
G02X330298Y212634I-1360J-26D01*
G01X330256Y214834D01*
G02X332976Y214886I1360J26D01*
G01X333018Y212687D01*
G37*
G36*
G01X354948Y210837D02*
G02X352240Y210578I-1354J-129D01*
G01X352031Y212769D01*
G02X354739Y213027I1354J129D01*
G01X354948Y210837D01*
G37*
G36*
G01X346240Y210141D02*
X346224Y210306D01*
X346295Y212525D01*
X346321Y212689D01*
G02X349017Y212612I1343J-213D01*
G01X349033Y212447D01*
X348962Y210234D01*
X348954Y210226D01*
X348947Y210154D01*
G02X346240Y210141I-1354J123D01*
G37*
G36*
G01X357162Y209968D02*
X357131Y210131D01*
X357014Y212358D01*
X357026Y212523D01*
G02X359740Y212498I1356J-97D01*
G01X359750Y212299D01*
X359761D01*
X359866Y210293D01*
X359859Y210286D01*
X359858Y210204D01*
G02X357162Y209968I-1360J16D01*
G37*
G36*
G01X337607Y209430D02*
X337566Y211648D01*
G02X340286Y211699I1360J26D01*
G01X340327Y209480D01*
G02X337607Y209430I-1360J-25D01*
G37*
G36*
G01X53370Y187640D02*
G02X50350I-1510J0D01*
G01Y191411D01*
G02X53370Y191410I1510J-1D01*
G01Y187640D01*
G37*
G36*
G01X200951Y187570D02*
G02X197931Y187525I-1510J-23D01*
G01X197882Y190925D01*
G02X200902Y190969I1510J22D01*
G01X200951Y187570D01*
G37*
G36*
G01X59379Y185890D02*
G02Y182870I0J-1510D01*
G01X55719D01*
G02X55720Y185890I1J1510D01*
G01X59379D01*
G37*
G36*
G01X241407Y180504D02*
G02X238393Y180697I-1507J97D01*
G01X238612Y184090D01*
G02X241626Y183896I1507J-97D01*
G01X241407Y180504D01*
G37*
G36*
G01X170910Y175350D02*
G02Y172330I0J-1510D01*
G01X167139D01*
G02X167140Y175350I1J1510D01*
G01X170910D01*
G37*
G36*
G01X177194Y171390D02*
G02X177125Y174410I-35J1510D01*
G01X180897Y174495D01*
G02X180965Y171475I34J-1510D01*
G01X177194Y171390D01*
G37*
G36*
G01X195638Y148605D02*
G02X193608Y150841I-1015J1118D01*
G01X196115Y153119D01*
X196116Y153120D01*
G02X198155Y150892I1024J-1110D01*
G01X195638Y148605D01*
G37*
G36*
G01X236385Y139289D02*
G02X233365Y139290I-1510J1D01*
G01Y143060D01*
G02X236385I1510J0D01*
G01Y139289D01*
G37*
G36*
G01X210551Y140538D02*
G02X210542Y137518I-5J-1510D01*
G01X206785Y137530D01*
G02X206795Y140550I5J1510D01*
G01X210551Y140538D01*
G37*
G36*
G01X205380Y135710D02*
G02Y132690I0J-1510D01*
G01X201898D01*
G02X201899Y135710I1J1510D01*
G01X205380D01*
G37*
G36*
G01X152180Y115499D02*
G02X149160Y115500I-1510J1D01*
G01Y118900D01*
G02X152180I1510J0D01*
G01Y115499D01*
G37*
G36*
G01X210769Y113771D02*
G02X207749I-1510J0D01*
G01Y117431D01*
G02X210769Y117430I1510J-1D01*
G01Y113771D01*
G37*
G36*
G01X273710Y108360D02*
G02X270690Y108345I-1510J-7D01*
G01X270675Y111824D01*
G02X273695Y111838I1510J7D01*
G01X273710Y108360D01*
G37*
G36*
G01X197845Y81870D02*
G02Y78850I0J-1510D01*
G01X194074D01*
G02X194075Y81870I1J1510D01*
G01X197845D01*
G37*
G36*
G01X82886Y62489D02*
G02X82885Y59469I-1J-1510D01*
G01X79115D01*
G02Y62489I0J1510D01*
G01X82886D01*
G37*
G36*
G01X290200Y59410D02*
G02Y56390I0J-1510D01*
G01X286799D01*
G02X286800Y59410I1J1510D01*
G01X290200D01*
G37*
G36*
G01X271000Y59010D02*
G02Y55990I0J-1510D01*
G01X267999D01*
G02X268000Y59010I1J1510D01*
G01X271000D01*
G37*
G36*
G01X319201Y58910D02*
G02X319200Y55890I-1J-1510D01*
G01X315800D01*
G02Y58910I0J1510D01*
G01X319201D01*
G37*
G36*
G01X308200D02*
G02Y55890I0J-1510D01*
G01X304799D01*
G02X304800Y58910I1J1510D01*
G01X308200D01*
G37*
G36*
G01X135001D02*
G02X135000Y55890I-1J-1510D01*
G01X131600D01*
G02Y58910I0J1510D01*
G01X135001D01*
G37*
G36*
G01X119201D02*
G02X119200Y55890I-1J-1510D01*
G01X115800D01*
G02Y58910I0J1510D01*
G01X119201D01*
G37*
G36*
G01X327400Y56410D02*
G02Y53390I0J-1510D01*
G01X323999D01*
G02X324000Y56410I1J1510D01*
G01X327400D01*
G37*
G36*
G01X208701D02*
G02X208700Y53390I-1J-1510D01*
G01X205300D01*
G02Y56410I0J1510D01*
G01X208701D01*
G37*
G36*
G01X166464Y55910D02*
G02X166463Y52890I-1J-1510D01*
G01X163063D01*
G02Y55910I0J1510D01*
G01X166464D01*
G37*
G36*
G01X150716D02*
G02X150715Y52890I-1J-1510D01*
G01X147315D01*
G02Y55910I0J1510D01*
G01X150716D01*
G37*
G36*
G01X103451D02*
G02X103450Y52890I-1J-1510D01*
G01X100050D01*
G02Y55910I0J1510D01*
G01X103451D01*
G37*
G36*
G01X88700D02*
G02Y52890I0J-1510D01*
G01X85299D01*
G02X85300Y55910I1J1510D01*
G01X88700D01*
G37*
G36*
G01X174061Y51110D02*
G02X174060Y48090I-1J-1510D01*
G01X170290D01*
G02Y51110I0J1510D01*
G01X174061D01*
G37*
G36*
G01X159060Y50120D02*
G02Y47100I0J-1510D01*
G01X155289D01*
G02X155290Y50120I1J1510D01*
G01X159060D01*
G37*
G36*
G01X236211Y44567D02*
G02Y41547I0J-1510D01*
G01X232590D01*
G02X232591Y44567I1J1510D01*
G01X236211D01*
G37*
G36*
G01X331931Y42505D02*
G02Y39485I0J-1510D01*
G01X328302D01*
G02X328303Y42505I1J1510D01*
G01X331931D01*
G37*
G36*
G01X316254Y42200D02*
G02Y39180I0J-1510D01*
G01X312483D01*
G02X312484Y42200I1J1510D01*
G01X316254D01*
G37*
G36*
G01X300506Y42000D02*
G02Y38980I0J-1510D01*
G01X296735D01*
G02X296736Y42000I1J1510D01*
G01X300506D01*
G37*
G36*
G01X284758D02*
G02Y38980I0J-1510D01*
G01X280987D01*
G02X280988Y42000I1J1510D01*
G01X284758D01*
G37*
G36*
G01X268911D02*
G02X268910Y38980I-1J-1510D01*
G01X265140D01*
G02Y42000I0J1510D01*
G01X268911D01*
G37*
G36*
G01X198073Y41905D02*
G02Y38885I0J-1510D01*
G01X194444D01*
G02X194445Y41905I1J1510D01*
G01X198073D01*
G37*
G36*
G01X245386Y41867D02*
G02X245385Y38847I-1J-1510D01*
G01X241765D01*
G02Y41867I0J1510D01*
G01X245386D01*
G37*
G36*
G01X190267D02*
G02Y38847I0J-1510D01*
G01X186646D01*
G02X186647Y41867I1J1510D01*
G01X190267D01*
G37*
G36*
G01X174519D02*
G02Y38847I0J-1510D01*
G01X170898D01*
G02X170899Y41867I1J1510D01*
G01X174519D01*
G37*
G36*
G01X158771D02*
G02Y38847I0J-1510D01*
G01X155150D01*
G02X155151Y41867I1J1510D01*
G01X158771D01*
G37*
G36*
G01X143024D02*
G02X143023Y38847I-1J-1510D01*
G01X139403D01*
G02Y41867I0J1510D01*
G01X143024D01*
G37*
G36*
G01X127276D02*
G02X127275Y38847I-1J-1510D01*
G01X123655D01*
G02Y41867I0J1510D01*
G01X127276D01*
G37*
G36*
G01X111528D02*
G02X111527Y38847I-1J-1510D01*
G01X107907D01*
G02Y41867I0J1510D01*
G01X111528D01*
G37*
G36*
G01X95779D02*
G02Y38847I0J-1510D01*
G01X92158D01*
G02X92159Y41867I1J1510D01*
G01X95779D01*
G37*
G36*
G01X80031D02*
G02Y38847I0J-1510D01*
G01X76410D01*
G02X76411Y41867I1J1510D01*
G01X80031D01*
G37*
G36*
G01X319026Y236350D02*
X316069D01*
G02Y239050I-69J1350D01*
G01X319031D01*
G02Y236350I69J-1350D01*
G01X319026D01*
G37*
G36*
G01X329939Y236762D02*
X329942Y236759D01*
X332041Y234668D01*
X332045Y234664D01*
G02X330148Y232742I-903J-1006D01*
G01X330145Y232745D01*
X328036Y234845D01*
X328033Y234848D01*
G02X329939Y236762I911J999D01*
G37*
G36*
G01X318550Y215226D02*
Y213169D01*
G02X315850I-1350J-69D01*
G01Y215231D01*
G02X318550I1350J69D01*
G01Y215226D01*
G37*
G36*
G01X322950Y210926D02*
Y208769D01*
G02X320250I-1350J-69D01*
G01Y210931D01*
G02X322950I1350J69D01*
G01Y210926D01*
G37*
G36*
G01X36300Y212122D02*
Y208373D01*
G02X33300I-1500J-73D01*
G01Y212127D01*
G02X36300I1500J73D01*
G01Y212122D01*
G37*
G36*
G01X33500Y203122D02*
Y199373D01*
G02X30500I-1500J-73D01*
G01Y203127D01*
G02X33500I1500J73D01*
G01Y203122D01*
G37*
G36*
G01X33637Y194000D02*
Y183653D01*
X33780Y183610D01*
G02X34850Y180100I-630J-2110D01*
G03X34879Y179817I154J-127D01*
G02X33809Y175920I-1379J-1717D01*
G01X33637Y175895D01*
Y172000D01*
X20137D01*
Y194000D01*
X33637D01*
G37*
G36*
G01X307505Y124052D02*
X307509D01*
X309573Y124142D01*
X309578D01*
G02X309696Y121444I122J-1346D01*
G01X309691D01*
X307626Y121354D01*
X307621Y121353D01*
G02X307505Y124052I-121J1347D01*
G37*
G36*
G01X309107Y116351D02*
X307051Y116374D01*
X307046D01*
G02X307077Y119074I-52J1351D01*
G01X307081D01*
X309137Y119051D01*
X309142D01*
G02X309111Y116351I52J-1351D01*
G01X309107D01*
G37*
G36*
G01X253422Y56400D02*
X250573D01*
G02Y59400I-73J1500D01*
G01X253427D01*
G02Y56400I73J-1500D01*
G01X253422D01*
G37*
G36*
G01X261922Y56300D02*
X259073D01*
G02Y59300I-73J1500D01*
G01X261927D01*
G02Y56300I73J-1500D01*
G01X261922D01*
G37*
G36*
G01X197622Y52900D02*
X194773D01*
G02Y55900I-73J1500D01*
G01X197627D01*
G02Y52900I73J-1500D01*
G01X197622D01*
G37*
G36*
G01X181722D02*
X179073D01*
G02Y55900I-73J1500D01*
G01X181727D01*
G02Y52900I73J-1500D01*
G01X181722D01*
G37*
G36*
G01X189622Y52800D02*
X186938D01*
G02Y55800I-73J1500D01*
G01X189627D01*
G02Y52800I73J-1500D01*
G01X189622D01*
G37*
G36*
G01X361889Y179663D02*
X362023Y179584D01*
X366689Y184250D01*
X380838D01*
G02X383140Y183479I962J-950D01*
G01X383149Y183412D01*
X384716Y181845D01*
G03X385398Y182128I282J283D01*
G01Y197749D01*
X386898Y199249D01*
Y224540D01*
X386750Y224689D01*
Y225311D01*
X388075Y226636D01*
X388006Y226766D01*
G02X389834Y228594I1194J634D01*
G01X389964Y228525D01*
X403689Y242250D01*
X532689D01*
X539250Y248811D01*
Y255311D01*
X560689Y276750D01*
X655811D01*
X664750Y267811D01*
Y255689D01*
X655750Y246689D01*
Y236689D01*
X624616Y205555D01*
X624707Y205419D01*
G02X621522Y202461I-1834J-1219D01*
G01X617327Y198266D01*
G02X615361Y196093I-1227J-865D01*
G01X615228Y196167D01*
X606723Y187662D01*
X606822Y187524D01*
G02X604726Y185428I-1222J-874D01*
G01X604588Y185527D01*
X600319Y181258D01*
X600407Y181122D01*
G02X598328Y179043I-1257J-822D01*
G01X598192Y179131D01*
X596811Y177750D01*
X476689D01*
X475040Y179398D01*
X465749D01*
X464749Y178398D01*
X429749D01*
X427749Y176398D01*
X423143D01*
X422351Y176003D01*
X422249Y175900D01*
X422144D01*
X422141Y175898D01*
X422139D01*
X422046Y175852D01*
X421907Y175898D01*
X401602D01*
Y170751D01*
X400249Y169398D01*
X392749D01*
X392102Y168751D01*
Y146249D01*
X392749Y145602D01*
X400749D01*
X405102Y141249D01*
Y133102D01*
X409251D01*
X410251Y134102D01*
X437249D01*
X439749Y131602D01*
X441749D01*
X450749Y122602D01*
X463540D01*
X463689Y122750D01*
X464311D01*
X468811Y118250D01*
X635811D01*
X664811Y89250D01*
X739811D01*
X772250Y56811D01*
Y21009D01*
X772257Y20707D01*
X772250Y20700D01*
Y20689D01*
X772036Y20476D01*
X761750Y9700D01*
Y9689D01*
X761536Y9476D01*
X761328Y9257D01*
X761318D01*
X761311Y9250D01*
X761009D01*
X760707Y9243D01*
X760700Y9250D01*
X598189D01*
X569689Y37750D01*
X532689D01*
X516689Y53750D01*
X449189D01*
X438750Y64189D01*
X432129Y70811D01*
X426189Y76750D01*
X396797D01*
X396786Y76740D01*
X396488Y76750D01*
X396189D01*
X396179Y76760D01*
X396165D01*
X395961Y76978D01*
X395750Y77189D01*
Y77203D01*
X388240Y85214D01*
X388260Y85835D01*
X388398Y85965D01*
Y96251D01*
X382898Y101751D01*
Y110250D01*
X362311D01*
X351750Y99689D01*
Y84811D01*
X365750Y70811D01*
Y64189D01*
X361311Y59750D01*
X337689D01*
X334250Y63189D01*
Y83811D01*
X340250Y89811D01*
Y97689D01*
X337250Y100689D01*
Y103811D01*
X348250Y114811D01*
Y120311D01*
X350250Y122311D01*
Y128189D01*
X348250Y130189D01*
Y135811D01*
X349806Y137367D01*
X349706Y137506D01*
G02X351594Y139394I1094J794D01*
G01X351733Y139294D01*
X357250Y144811D01*
Y152311D01*
X360250Y155311D01*
Y159181D01*
G02Y159319I1350J69D01*
G01Y167984D01*
X360237Y168018D01*
G02Y168982I1263J482D01*
G01X360250Y169016D01*
Y174484D01*
X360237Y174518D01*
G02Y175482I1263J482D01*
G01X360250Y175516D01*
Y177538D01*
G02X361889Y179663I950J962D01*
G37*
G54D41*
X37600Y198800D03*
Y203700D03*
X40400Y207800D03*
Y212700D03*
G54D38*
X144000Y67875D03*
Y147125D03*
G54D37*
X42717Y270472D03*
X235630Y75590D03*
X492520Y262598D03*
G54D39*
X235630Y174016D03*
X498425Y22798D03*
X755512Y262598D03*
G54D36*
X42717Y191732D03*
G54D40*
X804032Y27032D03*
Y67032D03*
G54D33*
X350197Y231103D03*
G54D34*
X11500Y68500D03*
X12000Y279000D03*
X816000Y280000D03*
G54D35*
X45669Y77185D03*
Y172460D03*
%LPC*%
G75*
G36*
G01X361750Y160603D02*
Y167163D01*
X361892Y167206D01*
G03Y169794I-392J1294D01*
G01X361750Y169837D01*
Y173663D01*
X361892Y173706D01*
G03Y176294I-392J1294D01*
G01X361750Y176337D01*
Y177189D01*
X361911Y177350D01*
G03X362339Y177771I-711J1150D01*
G01X362350Y177789D01*
X367311Y182750D01*
X380559D01*
X380616Y182647D01*
G03X382252Y182026I1184J653D01*
G01X382371Y182068D01*
X383607Y180832D01*
X383540Y180702D01*
G03X385362Y178880I1200J-622D01*
G01X385492Y178947D01*
X385689Y178750D01*
X385901D01*
X388751Y175900D01*
X400400D01*
Y171249D01*
X399751Y170600D01*
X392251D01*
X390900Y169249D01*
Y145751D01*
X392251Y144400D01*
X400251D01*
X403900Y140751D01*
Y133100D01*
X395751D01*
X391400Y128749D01*
Y127249D01*
X390751Y126600D01*
X388249D01*
X387249Y127600D01*
X384251D01*
X382900Y126249D01*
Y111750D01*
X361689D01*
X350250Y100311D01*
Y84189D01*
X364250Y70189D01*
Y64811D01*
X360689Y61250D01*
X338311D01*
X335803Y63758D01*
X335802Y63839D01*
G03X335754Y64256I-2202J-42D01*
G01X335750Y64276D01*
Y83189D01*
X341750Y89189D01*
Y98311D01*
X338750Y101311D01*
Y103189D01*
X349750Y114189D01*
Y119689D01*
X351750Y121689D01*
Y128811D01*
X349750Y130811D01*
Y135189D01*
X358750Y144189D01*
Y151689D01*
X361750Y154689D01*
Y157897D01*
X361905Y157933D01*
G03Y160567I-305J1317D01*
G01X361750Y160603D01*
G37*
G36*
G01X386751Y126400D02*
X387751Y125400D01*
X391249D01*
X392600Y126751D01*
Y128251D01*
X396249Y131900D01*
X409749D01*
X410749Y132900D01*
X436751D01*
X439251Y130400D01*
X441251D01*
X450251Y121400D01*
X463539D01*
X468189Y116750D01*
X635189D01*
X655191Y96749D01*
X664189Y87750D01*
X739189D01*
X770750Y56189D01*
Y21300D01*
X760679Y10750D01*
X598811D01*
X570311Y39250D01*
X533311D01*
X517311Y55250D01*
X449811D01*
X426811Y78250D01*
X396825D01*
X389600Y85957D01*
Y96749D01*
X384100Y102249D01*
Y110539D01*
X384250Y110689D01*
Y111311D01*
X384100Y111461D01*
Y125751D01*
X384749Y126400D01*
X386751D01*
G37*
G36*
G01X614624Y197685D02*
X604937Y187998D01*
X604910Y187984D01*
G03X604266Y187340I690J-1334D01*
G01X604252Y187313D01*
X598659Y181720D01*
X598619Y181705D01*
G03X597745Y180831I531J-1405D01*
G01X597730Y180791D01*
X596189Y179250D01*
X477311D01*
X475811Y180750D01*
X475189D01*
X475039Y180600D01*
X465251D01*
X464251Y179600D01*
X429251D01*
X427251Y177600D01*
X423097D01*
X422954Y177648D01*
X422858Y177600D01*
X422751D01*
X422645Y177493D01*
X421858Y177100D01*
X389249D01*
X386750Y179599D01*
Y179811D01*
X386600Y179961D01*
Y197251D01*
X388100Y198751D01*
Y224539D01*
X389707Y226146D01*
X389742Y226161D01*
G03X390439Y226858I-542J1239D01*
G01X390454Y226893D01*
X404311Y240750D01*
X533311D01*
X540750Y248189D01*
Y254689D01*
X561311Y275250D01*
X655189D01*
X663250Y267189D01*
Y256311D01*
X655129Y248189D01*
X654250Y247311D01*
Y237311D01*
X623301Y206362D01*
X623201Y206377D01*
G03X620696Y203872I-328J-2177D01*
G01X620711Y203772D01*
X615815Y198876D01*
X615759Y198863D01*
G03X614637Y197741I341J-1463D01*
G01X614624Y197685D01*
G37*
%LPD*%
G75*
G54D37*
X761417Y22798D03*
G54D15*
X17500Y190200D03*
X16844Y203100D03*
X13090Y231129D03*
Y234899D03*
X7600Y240861D03*
Y237091D03*
X13590Y242940D03*
Y254751D03*
X7600Y252672D03*
Y248902D03*
Y260713D03*
X13590Y258521D03*
Y246710D03*
X16900Y269000D03*
X7600Y264483D03*
X28400Y81400D03*
X30000Y136000D03*
X29700Y141200D03*
X26500Y181800D03*
X33500Y178100D03*
X33150Y181500D03*
X29400Y180000D03*
X23100Y181800D03*
X33500Y196100D03*
X32000Y203200D03*
Y199300D03*
X41200Y90300D03*
X42000Y96000D03*
X41500Y100800D03*
X40500Y124300D03*
X37600Y198800D03*
X37900Y195300D03*
X40400Y212700D03*
X34800Y208300D03*
X40400Y207800D03*
X34800Y212200D03*
X37600Y203700D03*
X44861Y227261D03*
X37900Y219000D03*
Y222500D03*
Y229500D03*
Y226000D03*
Y240000D03*
Y243500D03*
Y233000D03*
X38000Y236500D03*
X44400Y250400D03*
X37900Y257500D03*
Y254000D03*
Y247000D03*
X38000Y250500D03*
X46800Y274500D03*
X62900Y79900D03*
X60800Y87500D03*
X53500Y120400D03*
X57600Y136900D03*
X56100Y130700D03*
X52643Y130800D03*
X58000Y141750D03*
X58800Y177000D03*
X51860Y187640D03*
Y191410D03*
X59379Y184380D03*
X55720D03*
X57400Y210700D03*
X57009Y230009D03*
X57600Y226600D03*
X57500Y223200D03*
X57287Y219806D03*
X56724Y243300D03*
X56800Y249613D03*
X58102Y246471D03*
X57800Y253900D03*
X50000Y270000D03*
X57800Y264100D03*
X64700Y272500D03*
X57800Y267500D03*
X80031Y40357D03*
X76411D03*
X79700Y67500D03*
X79115Y60979D03*
X69235Y99735D03*
X68200Y94900D03*
Y91500D03*
X66500Y128000D03*
X65500Y123800D03*
X74800Y191000D03*
X72600Y244800D03*
X75600Y246700D03*
X79000Y246900D03*
X69400Y246000D03*
X75300Y259900D03*
X78200Y275600D03*
X71800Y268800D03*
X66800Y275200D03*
X74000Y271400D03*
X92159Y40357D03*
X88700Y54400D03*
X85300D03*
X90600Y63200D03*
X94000Y63300D03*
X82885Y60979D03*
X90000Y91000D03*
X91500Y84000D03*
X94500Y76200D03*
X89800Y87300D03*
X86100Y97700D03*
X90500Y101000D03*
X86500Y113500D03*
X80500D03*
X85500Y135400D03*
X83500Y191000D03*
X86900D03*
X84700Y197100D03*
X92900Y204008D03*
X89500Y204000D03*
X85898Y200598D03*
X95200Y216200D03*
X90812Y215000D03*
X80563Y214700D03*
X88900Y246700D03*
X82400Y246600D03*
X82100Y259600D03*
X80500Y269500D03*
X83900D03*
X95779Y40357D03*
X107907D03*
X109700Y60000D03*
X103450Y54400D03*
X100050D03*
X109600Y63700D03*
X96200Y60700D03*
X97900Y76200D03*
X106100Y158700D03*
X97100Y189200D03*
X110000Y201900D03*
X107740Y204460D03*
X102000Y203200D03*
X100600Y221100D03*
X110166Y239500D03*
X109500Y258300D03*
X97600Y246500D03*
X104900Y248800D03*
X120000Y40700D03*
X123655Y40357D03*
X111527D03*
X120200Y45610D03*
X119200Y57400D03*
X115800D03*
X111200Y67200D03*
X121170Y80900D03*
X121295Y77502D03*
X126000Y86200D03*
X125787Y78813D03*
X120700Y135500D03*
X118500Y125500D03*
X112550Y142800D03*
X119600Y143300D03*
X111900Y209000D03*
X112800Y225400D03*
X112700Y221200D03*
Y231400D03*
X136600Y44800D03*
X139403Y40357D03*
X127275D03*
X138000Y49800D03*
X138574Y57924D03*
X131600Y57400D03*
X135000D03*
X136469Y89902D03*
X130315Y90533D03*
X134200Y86100D03*
X137138Y76512D03*
X129300Y84900D03*
X136600Y93300D03*
X133558Y91779D03*
X136500Y104923D03*
X130000Y121000D03*
X136540Y108620D03*
X133975Y129141D03*
X130563Y125200D03*
X127500Y129180D03*
X126950Y125200D03*
X133786Y134700D03*
X130300Y135000D03*
X135412Y141400D03*
X138600Y146300D03*
X131500Y149000D03*
X136156Y138025D03*
X131762Y141796D03*
X127200Y158700D03*
X137300Y158900D03*
X140800D03*
X140000Y195500D03*
X137100Y188900D03*
X128000Y203300D03*
X143023Y40357D03*
X155151D03*
X144995Y57995D03*
X155290Y48610D03*
X143688Y48350D03*
X147400Y60400D03*
X147315Y54400D03*
X150715D03*
X153000Y67800D03*
X150894Y76497D03*
X154294Y76506D03*
X150670Y102720D03*
X154550Y106200D03*
X151080Y99344D03*
X154550Y102800D03*
X150670Y115500D03*
Y118900D03*
X157229Y119218D03*
X153693Y124807D03*
X147808Y145208D03*
X142900Y138595D03*
X146400D03*
X150804Y158896D03*
X144500Y158900D03*
X146980Y200580D03*
X153000Y201900D03*
X153500Y210000D03*
X146396Y207675D03*
X142997Y207891D03*
X150000Y210100D03*
X146500Y236500D03*
X146000Y231000D03*
X155300Y254000D03*
X144200Y270700D03*
X158771Y40357D03*
X170899D03*
X159060Y48610D03*
X170290Y49600D03*
X166463Y54400D03*
X163063D03*
X164000Y65000D03*
X172199Y91591D03*
X172300Y107189D03*
X158305Y112180D03*
X157500Y149025D03*
X158500Y161820D03*
X161900Y161700D03*
X167581Y164084D03*
X170910Y173840D03*
X167140D03*
X165900Y181500D03*
X163700Y178900D03*
X165700Y254000D03*
X174519Y40357D03*
X186647D03*
X174060Y49600D03*
X186865Y54300D03*
X181800Y54400D03*
X179000D03*
X179800Y65700D03*
X176900Y67500D03*
X180700Y78500D03*
X174900Y77700D03*
X183726Y106353D03*
X187500Y106500D03*
X173000Y97000D03*
X183344Y94056D03*
X179400Y94200D03*
X181732Y97500D03*
X178000Y97300D03*
X175787Y127000D03*
X176700Y144875D03*
X177200Y148700D03*
X181000Y167500D03*
X180931Y172985D03*
X177159Y172900D03*
X186300Y172400D03*
X174739Y207381D03*
X187000Y209500D03*
X198073Y40395D03*
X194445D03*
X190267Y40357D03*
X189700Y54300D03*
X197700Y54400D03*
X194700D03*
X190100Y68700D03*
X193500D03*
X194075Y80360D03*
X197845D03*
X202200Y89500D03*
X191500Y94100D03*
X188900Y91800D03*
X193005Y97155D03*
X195989Y95300D03*
X189106Y97235D03*
X201650Y111200D03*
X201899Y134200D03*
X194900Y124200D03*
X197140Y152010D03*
X194623Y149723D03*
X191200Y181068D03*
X199441Y187547D03*
X199392Y190947D03*
X202761Y186811D03*
X195630Y192770D03*
X198198Y206374D03*
X194800Y206100D03*
X201596Y206504D03*
X195000Y234000D03*
X205300Y54900D03*
X208700D03*
X214942Y67242D03*
X211600Y82100D03*
X212300Y85500D03*
X207200Y106000D03*
X209259Y113771D03*
Y117430D03*
X206605Y121741D03*
X209900Y120900D03*
X205380Y134200D03*
X210547Y139028D03*
X206790Y139040D03*
X215100Y194200D03*
X207861Y188540D03*
X215100Y199400D03*
X205000Y206500D03*
X215384Y202984D03*
X216000Y219500D03*
X208800D03*
X212500D03*
X206000Y234000D03*
X229300Y42950D03*
X232591Y43057D03*
X219900Y39100D03*
X223475Y53300D03*
X219899Y56800D03*
X233981Y59125D03*
X221400Y64500D03*
X230400Y63000D03*
X223800Y61700D03*
X230000Y66400D03*
X226500Y94450D03*
X227850Y97575D03*
X230875Y106300D03*
X227894Y104600D03*
X232600Y95300D03*
X227800Y101200D03*
X233452Y108588D03*
X228000Y108304D03*
Y139700D03*
X232921Y167505D03*
X227870Y170252D03*
X224200Y180200D03*
X232560Y204250D03*
X227000Y275500D03*
X236211Y43057D03*
X245385Y40357D03*
X241765D03*
X244400Y50600D03*
X235400Y63400D03*
X240297D03*
X243200Y73700D03*
X240300Y67200D03*
X246600Y73700D03*
X244759Y85200D03*
X236700Y88500D03*
X241200Y94900D03*
X244800Y100700D03*
X235075Y105600D03*
X234875Y139290D03*
Y143060D03*
X244715Y159785D03*
X239900Y180600D03*
X247596Y174667D03*
X240119Y183993D03*
X240100Y191000D03*
X246689Y196687D03*
X254600Y41100D03*
X265140Y40490D03*
X259000Y57800D03*
X250500Y57900D03*
X262000Y57800D03*
X253500Y57900D03*
X264500Y73100D03*
X253700Y75875D03*
X250300Y73800D03*
X264125Y79350D03*
X259820Y103454D03*
X262131Y100959D03*
X258634Y95850D03*
X263775Y140327D03*
X257977Y163423D03*
X264600Y173100D03*
X257687Y169870D03*
X253500Y174360D03*
X261300Y188300D03*
X253300Y189834D03*
X262700Y191500D03*
X261200Y209700D03*
X263600Y239850D03*
Y252700D03*
X257500Y266645D03*
X260500Y264630D03*
X269800Y44800D03*
X275300Y44900D03*
X278700Y44800D03*
X268910Y40490D03*
X278868Y56000D03*
X271000Y57500D03*
X268000D03*
X275200Y78700D03*
X275900Y88200D03*
X280100Y89100D03*
X272200Y108352D03*
X272185Y111831D03*
X278075Y116475D03*
X272300Y129442D03*
X268900Y129386D03*
X280400Y129225D03*
X272300Y149900D03*
X267187Y149800D03*
X278000Y141900D03*
X273900Y156198D03*
X270500Y163200D03*
X274100Y163300D03*
X267456Y160156D03*
X267100Y156200D03*
X272380Y159240D03*
X270500Y156250D03*
X268283Y173035D03*
X278300Y173300D03*
X276910Y189400D03*
X273060Y189374D03*
X266140Y191850D03*
X270341Y211835D03*
X278450Y216800D03*
X265259Y216659D03*
X270774Y222226D03*
X275400Y237900D03*
X267275Y253400D03*
X265500Y249300D03*
X269800Y250700D03*
X278700Y254240D03*
X275300Y254100D03*
X267000Y271300D03*
X284758Y40490D03*
X280988D03*
X286800Y57900D03*
X290200D03*
X288400Y94200D03*
X288100Y99500D03*
X281005Y99105D03*
X281475Y116475D03*
X286500Y119900D03*
X286600Y136000D03*
X287071Y173154D03*
X282950Y181350D03*
X282460Y189400D03*
X286300Y191885D03*
X293300Y212400D03*
X291201Y225025D03*
X287802Y225200D03*
X287600Y238100D03*
X287400Y254100D03*
X295500Y253500D03*
X281599Y261799D03*
X287250Y269250D03*
X296736Y40490D03*
X300506D03*
X300900Y46900D03*
X308200Y57400D03*
X304800D03*
X297150Y91100D03*
X309400Y82100D03*
X299800Y85950D03*
Y82300D03*
X304400Y88400D03*
X301300Y97000D03*
X301600Y93300D03*
X303400Y98500D03*
X303376Y95200D03*
X299300Y98500D03*
X296564Y136311D03*
Y127500D03*
X296531Y133061D03*
X301109Y146156D03*
X300700Y142850D03*
X297000Y160200D03*
X307231Y164059D03*
X310579Y182800D03*
X306612Y171882D03*
X304400Y182000D03*
X302591Y173906D03*
X309112Y171960D03*
X309200Y180500D03*
X305091Y173888D03*
X301745Y181788D03*
X307200Y182000D03*
X296600Y189100D03*
X305300Y203125D03*
X307300Y224900D03*
X304400D03*
X309900D03*
X298900Y253300D03*
X309400Y253600D03*
X306000D03*
X302600D03*
X304300Y262900D03*
X309000Y266700D03*
X311300Y277800D03*
X321900Y44000D03*
X312484Y40690D03*
X316254D03*
X314800Y48625D03*
X311950Y50800D03*
X320400Y48600D03*
X324000Y54900D03*
X324176Y48600D03*
X315800Y57400D03*
X319200D03*
X312400Y79700D03*
X312150Y100682D03*
X326000Y254100D03*
X315500D03*
X322500Y254200D03*
X319000D03*
X311400Y269200D03*
X326100Y267000D03*
X318600Y264300D03*
X313824Y280255D03*
X316945Y281606D03*
X316400Y276800D03*
X319400Y278800D03*
X322700Y277700D03*
X321600Y282500D03*
X325100Y281500D03*
X331931Y40995D03*
X328303D03*
X331300Y48475D03*
X327577D03*
X327400Y54900D03*
X333600Y63800D03*
X337000Y74202D03*
X356432Y43657D03*
X356971Y37700D03*
X349900Y263800D03*
X342600Y277900D03*
X364600Y44298D03*
X367497Y41042D03*
X363604D03*
X371457Y37642D03*
X367520D03*
X366484Y47129D03*
X362626Y47068D03*
X366700Y68700D03*
X369500Y237200D03*
Y240600D03*
X373000Y242300D03*
X369500Y234600D03*
X373000Y236000D03*
Y238900D03*
X369500Y244000D03*
X385300Y47000D03*
X388000Y72963D03*
X382700Y275300D03*
X386100D03*
X379300D03*
X394229Y241128D03*
X391788Y238760D03*
X399438Y243839D03*
X401838Y246248D03*
X390500Y268800D03*
X393000Y275000D03*
X400900Y273000D03*
X391000Y265000D03*
X417000Y258000D03*
X416128Y272896D03*
X425400Y9103D03*
X422000D03*
X428800D03*
X432200D03*
X430000Y21500D03*
Y27358D03*
X424543Y22208D03*
Y27900D03*
X426405Y25054D03*
X427000Y17000D03*
X423500Y16885D03*
X423000Y43900D03*
X430000Y30758D03*
X424536Y34800D03*
X430000Y34158D03*
X424599Y31300D03*
X422986Y40350D03*
X430000Y244450D03*
X426600D03*
X420000Y244000D03*
X420500Y257800D03*
X433129Y245783D03*
X423600Y246700D03*
X423000Y274000D03*
X433300Y274100D03*
X426600D03*
X429900Y274940D03*
X442100Y7006D03*
X437061Y10393D03*
X434900Y6925D03*
X446800Y9900D03*
X438300Y6925D03*
X449600Y5900D03*
X446200D03*
X446100Y18700D03*
X441390Y28680D03*
X436240Y26300D03*
X449734Y18681D03*
X441281Y17025D03*
X436100Y30900D03*
X436106Y34506D03*
X435700Y243250D03*
X440600Y274300D03*
X449400Y273700D03*
X436600Y275000D03*
X450200Y9800D03*
X451300Y21700D03*
X464000Y275200D03*
X460400D03*
X452500D03*
X469000D03*
X472400Y275100D03*
X466500Y272800D03*
X472101Y266090D03*
X475500Y265900D03*
X479000D03*
X493000Y119299D03*
X495400Y183500D03*
X482400Y266200D03*
X502000Y89000D03*
X498500Y88995D03*
X508000Y119500D03*
X511500D03*
X511200Y183400D03*
X500900D03*
X504400D03*
X510675Y209700D03*
X505315Y268500D03*
X497002Y275400D03*
X525740Y88960D03*
X522280Y89810D03*
X515502Y88998D03*
X518902Y88987D03*
X518200Y183400D03*
X526600Y183500D03*
X514800Y183400D03*
X513100Y234500D03*
X516500D03*
X528985Y89975D03*
X533267Y89634D03*
X539574Y88990D03*
X533000Y119500D03*
X536400D03*
X528100D03*
X528400Y145041D03*
X541550Y183550D03*
X534750Y183600D03*
X538150D03*
X530214Y183481D03*
X531500Y219500D03*
X541500Y234900D03*
X551800Y69600D03*
X548400Y69700D03*
X555199D03*
X556500Y89000D03*
X546349Y89512D03*
X552900Y89100D03*
X542950Y89400D03*
X555500Y183500D03*
X548354Y183600D03*
X544954D03*
X551754D03*
X548300Y209700D03*
X551700Y209800D03*
X550400Y222285D03*
X561999Y69700D03*
X558599D03*
X570715Y89100D03*
X566000D03*
X572845Y183300D03*
X566897Y183405D03*
X561900Y183600D03*
X564398Y183481D03*
X569395Y183300D03*
X558915Y183603D03*
X558300Y210000D03*
X561000Y222700D03*
X561196Y227366D03*
X569200Y223600D03*
X564200Y224000D03*
X575000Y89100D03*
X587500Y88913D03*
X578400Y89100D03*
X588600Y124700D03*
X584800Y183300D03*
X582254Y183313D03*
X576295Y183400D03*
X588475Y183300D03*
X578795D03*
X573600Y190100D03*
X586800Y213200D03*
X583800Y207200D03*
X580350Y207250D03*
X599500Y87500D03*
X590898Y89045D03*
X596845Y89624D03*
X593400Y126000D03*
X592200Y145000D03*
X595744Y145041D03*
X599150Y180300D03*
X593475Y183275D03*
X601750Y182500D03*
X590975Y183275D03*
X594350Y187725D03*
X591850D03*
X588800Y205900D03*
X591363Y208387D03*
X602800Y203225D03*
X601200Y207700D03*
X603964Y210400D03*
X612120Y121750D03*
X608360Y121800D03*
X608300Y144890D03*
X618500Y159000D03*
X605600Y186650D03*
X609345Y190100D03*
X607500Y188300D03*
X616100Y197400D03*
X634000Y97500D03*
X630700Y100500D03*
X627500Y104900D03*
X620000Y112575D03*
X624726Y107395D03*
X621100Y124900D03*
X625500Y159000D03*
X629000D03*
X622000D03*
X633319Y155008D03*
X631900Y175850D03*
X634748Y177708D03*
X633100Y198300D03*
X626300Y198250D03*
X629700Y198300D03*
X622873Y204200D03*
X642823Y88477D03*
X640677Y91115D03*
X638500Y94000D03*
X635000Y110500D03*
X638000Y107400D03*
X648500Y144000D03*
X636719Y154972D03*
X643500Y155000D03*
X640110Y155272D03*
X640461Y181410D03*
X642600Y186400D03*
X646000D03*
X636500Y198300D03*
X653600Y122400D03*
X656477Y148033D03*
X656642Y151430D03*
X656200Y144000D03*
X650500Y155000D03*
X661000Y173800D03*
X657722Y193800D03*
X661600Y197300D03*
X654851Y191978D03*
X663800Y199900D03*
X673100Y179455D03*
X673044Y190456D03*
X668732Y204555D03*
X666446Y202037D03*
X682600Y114300D03*
X689400Y178900D03*
X689547Y175500D03*
X686700Y187400D03*
X687456Y183944D03*
X705145Y93500D03*
X707209Y97500D03*
X698970Y118149D03*
X699241Y114759D03*
X709500Y143500D03*
X709900Y139900D03*
X701245Y183800D03*
X718900Y94000D03*
X726800Y95500D03*
X724200Y108400D03*
X714000Y118500D03*
X727448Y128893D03*
X714900Y131900D03*
X718200Y147000D03*
Y150400D03*
X718825Y155453D03*
X712700Y155978D03*
X724400Y176025D03*
X725500Y195500D03*
X727400Y227400D03*
X738000Y65700D03*
X731340Y82515D03*
X736900Y98500D03*
X730200Y94900D03*
X742100Y118200D03*
X736300Y118000D03*
X729400Y120200D03*
X732000Y122700D03*
X728900Y132976D03*
X727800Y136600D03*
X740300Y164700D03*
X727800Y176600D03*
X733000Y176200D03*
X739900Y212800D03*
X731000Y210200D03*
X739800Y216300D03*
X750100Y16100D03*
X752500Y49007D03*
X749500Y101500D03*
X751300Y118200D03*
X754000Y115100D03*
X748800Y115800D03*
X757900Y124700D03*
X743100Y195500D03*
X743000Y211000D03*
X744100Y221900D03*
X743800Y215900D03*
X758916Y104250D03*
X762304Y103957D03*
X765500Y112000D03*
X769800Y133000D03*
X759400Y131000D03*
X771300Y140200D03*
X766600Y139800D03*
X762000Y281000D03*
X765400D03*
X774500Y31307D03*
X778000D03*
X787600Y183300D03*
X787800Y179900D03*
X793000Y174500D03*
X805500Y128000D03*
G54D20*
X196800Y62600D03*
X199600Y160100D03*
X502500Y6200D03*
X538300Y15200D03*
X699000Y162255D03*
X756400Y110500D03*
X786500Y13500D03*
X782000Y137000D03*
X790500Y11000D03*
X799000Y121500D03*
Y125500D03*
X800400Y158500D03*
X799900Y168800D03*
X811000Y130000D03*
Y134000D03*
X809000Y149200D03*
X811000Y138000D03*
X811200Y141600D03*
X809500Y156900D03*
X809600Y160500D03*
X809700Y164300D03*
G54D13*
X15400Y118000D03*
X10900D03*
X15500Y122800D03*
X15000Y127500D03*
X11000Y122800D03*
X10500Y127500D03*
X11500Y163700D03*
Y159000D03*
X7000Y163700D03*
Y159000D03*
X33000Y105000D03*
X30200Y145000D03*
Y149200D03*
X34000Y161500D03*
X30300Y157600D03*
X30200Y153400D03*
X37500Y105000D03*
X42000D03*
X37500Y264000D03*
X63500Y43500D03*
Y57500D03*
Y48000D03*
Y52500D03*
X63200Y194900D03*
X68500Y47500D03*
X73500Y48000D03*
X68000Y52500D03*
X70900Y193800D03*
X82000Y177500D03*
X92800Y285600D03*
X104000Y106600D03*
Y115500D03*
Y111000D03*
X100000Y267400D03*
X100700Y262900D03*
X97500Y285450D03*
X102000D03*
X106500Y285550D03*
X110700D03*
X119400Y106700D03*
X123800Y102500D03*
X123900Y106700D03*
X119400Y102300D03*
Y115900D03*
Y111200D03*
X123900Y115900D03*
Y111200D03*
X113200Y146700D03*
X113100Y151000D03*
X117500Y146950D03*
X119000Y159100D03*
X114700Y158800D03*
X116500Y211200D03*
X134100Y96600D03*
X128500Y165000D03*
X129500Y252500D03*
X129000Y268000D03*
X166500Y241000D03*
X189000Y87700D03*
X192500Y161900D03*
X192600Y166700D03*
X201200Y164200D03*
X216261Y74846D03*
X212300Y157300D03*
X212600Y161500D03*
X217000Y252900D03*
X217200Y258000D03*
X226900Y133300D03*
X234525Y239250D03*
X229700Y234700D03*
X225300Y239200D03*
X234525Y243450D03*
X229725D03*
X225300Y243400D03*
X234525Y234800D03*
X225300D03*
X229675Y239000D03*
X221300Y255400D03*
X240130Y77300D03*
X236400Y95100D03*
X240565Y113365D03*
X249350Y199400D03*
X247500Y239250D03*
X243300Y235050D03*
X247500Y243450D03*
X243300D03*
X238900D03*
X243300Y239250D03*
X247500Y235050D03*
X238925Y235000D03*
Y239200D03*
X258400Y65600D03*
X252350Y202350D03*
X251700Y239250D03*
Y243450D03*
X253000Y267000D03*
X278200Y281350D03*
X294800Y94100D03*
X282686Y281336D03*
X339638Y67138D03*
X334500Y266300D03*
X334300Y270500D03*
X335700Y278751D03*
X331500D03*
X345089Y73089D03*
X343600Y270500D03*
X371400Y42500D03*
X371500Y47000D03*
X380000Y38100D03*
X375600Y42500D03*
X380300D03*
X375700Y47000D03*
X380295Y46779D03*
X505200Y215000D03*
X496711Y248999D03*
X527000Y225500D03*
X600900Y230200D03*
X615700D03*
X630000Y55300D03*
X623400Y230100D03*
X640500Y55000D03*
X655133Y55833D03*
X653000Y93000D03*
X725632Y49600D03*
X721950Y51950D03*
X722000Y74500D03*
X717000D03*
X715000Y80300D03*
X714500Y85500D03*
X732000Y63500D03*
X739500Y75500D03*
X770500Y13007D03*
X759000Y37507D03*
X787500Y93000D03*
X783000D03*
X785830Y188700D03*
X785400Y202800D03*
X789000Y204979D03*
X789200Y214200D03*
Y209800D03*
X784500Y222500D03*
X789000Y223500D03*
X789200Y218700D03*
X786000Y228000D03*
Y232400D03*
X786200Y236900D03*
X786300Y241500D03*
X785000Y245800D03*
Y250200D03*
Y254900D03*
X792000Y83000D03*
X796500D03*
X792000Y87700D03*
X796500D03*
X799200Y98600D03*
X803100Y106000D03*
X799200Y102800D03*
X799000Y107100D03*
X803500Y116700D03*
Y112500D03*
X799000Y116100D03*
Y111900D03*
X789910Y187679D03*
X794110D03*
X798310Y187779D03*
X793500Y204979D03*
Y223500D03*
X793200Y228400D03*
Y232600D03*
Y237200D03*
Y242400D03*
X793300Y247200D03*
X795300Y260800D03*
X795400Y251700D03*
X795300Y256500D03*
Y265000D03*
X810100Y275000D03*
X812035Y271067D03*
X810100Y267339D03*
X812000Y263500D03*
G54D18*
X42717Y270472D03*
X235630Y75590D03*
X492520Y262598D03*
D03*
X761417Y22798D03*
D03*
X804032Y27032D03*
X794032D03*
X804032Y37032D03*
Y47032D03*
X794032Y37032D03*
Y47032D03*
X804032Y57032D03*
X794032D03*
X804032Y67032D03*
X794032D03*
G54D22*
X235630Y174016D03*
X498425Y22798D03*
D03*
X755512Y262598D03*
D03*
G54D24*
X303610Y110800D03*
X309000Y114700D03*
X306700D03*
X309194Y117700D03*
X306994Y117725D03*
X304149Y128349D03*
X307854Y130539D03*
X309700Y122796D03*
X309500Y132925D03*
X307298Y132697D03*
X307500Y122700D03*
X305050Y151150D03*
X309000Y137600D03*
X306961Y153717D03*
X306696Y158610D03*
X309000Y158806D03*
X309220Y153698D03*
X305800Y195400D03*
X303500D03*
X303480Y189100D03*
X301300Y188700D03*
X309700Y187997D03*
X307500Y188000D03*
X317641Y90956D03*
X325081Y100631D03*
X322075Y100650D03*
X323120Y92400D03*
X319520Y92419D03*
X318900Y98000D03*
X317600Y93625D03*
X326162Y91438D03*
X315950Y98650D03*
X320992Y112180D03*
X319096Y113300D03*
X319418Y123225D03*
X315451Y123219D03*
X323900Y129900D03*
X325418Y127349D03*
X325746Y133702D03*
X323300Y147046D03*
X326322Y138434D03*
X325763Y141958D03*
X325200Y149319D03*
X319704Y162804D03*
X323000Y153900D03*
X324029Y166384D03*
X326234Y153969D03*
X323500Y180063D03*
X323121Y182913D03*
X326408Y182292D03*
X316844Y196010D03*
X319801Y194890D03*
X326550Y191600D03*
X322256Y198618D03*
X323331Y196696D03*
X325642Y202325D03*
X321600Y208700D03*
Y211000D03*
X317200Y213100D03*
Y215300D03*
X316000Y237700D03*
X319100D03*
X329300Y87300D03*
X331200Y88600D03*
X330100Y100200D03*
Y98000D03*
X336750Y93500D03*
Y95704D03*
X328000Y92700D03*
X330900Y93400D03*
X333313Y103693D03*
X339500Y102000D03*
X329415Y119923D03*
X333601Y120500D03*
X333534Y118040D03*
X333434Y106668D03*
X341200Y112569D03*
X338768Y116755D03*
Y119755D03*
X329308Y122386D03*
X338329Y135665D03*
X329031Y125428D03*
X335303Y135178D03*
X336900Y127600D03*
X333977Y127678D03*
X327854Y130434D03*
X338470Y138177D03*
X335450Y150900D03*
X327963Y142008D03*
X335514Y138220D03*
X338320Y141300D03*
X327390Y149106D03*
X336920Y146130D03*
X329421Y138228D03*
X327696Y146108D03*
X330163Y142008D03*
X332478Y138255D03*
X341342Y138224D03*
X333750Y145950D03*
X339491Y143163D03*
X329800Y150800D03*
X332000D03*
X330300Y158546D03*
X339784Y161847D03*
X335499Y153846D03*
X327800Y161500D03*
X336900Y161600D03*
X336800Y164434D03*
X341390Y153991D03*
X329161Y153830D03*
X335964Y158512D03*
X341400Y156700D03*
X331000Y164500D03*
X330900Y161700D03*
X333000Y158300D03*
X339747Y164478D03*
X339300Y174100D03*
X330821Y177402D03*
X329442Y169463D03*
X327708Y177241D03*
X332353Y169522D03*
X337000Y174102D03*
X327600Y174174D03*
X330027Y174119D03*
X334700Y174100D03*
X336915Y177423D03*
X337863Y180545D03*
X330280Y180900D03*
X332500D03*
X335400Y196300D03*
X337800Y189200D03*
X326850Y193900D03*
X329972Y196400D03*
Y193559D03*
X333996Y192063D03*
X334707Y189383D03*
X337800Y192200D03*
X329313Y188000D03*
X335739Y199317D03*
X336500Y204600D03*
X338926Y211674D03*
X338967Y209455D03*
X331658Y212660D03*
X327216Y203902D03*
X328510Y218320D03*
X327024Y220024D03*
X337307Y217961D03*
X331616Y214860D03*
X337341Y215731D03*
X328945Y235846D03*
X331142Y233658D03*
X344523Y98477D03*
X344500Y94000D03*
X347230Y100190D03*
X351342Y114158D03*
X346596Y118163D03*
Y115163D03*
X351000Y111700D03*
X355175Y108212D03*
X348076Y108910D03*
X343570Y112561D03*
X346495Y130000D03*
X349149Y124141D03*
X354333Y125665D03*
X343000Y126200D03*
X343146Y128473D03*
X347641Y133479D03*
X342533Y133822D03*
X346300Y143000D03*
X355447Y146528D03*
X344500Y141700D03*
X348675Y143326D03*
X350800Y138300D03*
X348743Y146072D03*
X346000Y146043D03*
X346450Y149120D03*
X348432Y164844D03*
X346944Y156775D03*
X350550Y153280D03*
X344300Y153800D03*
X344090Y156690D03*
X352000Y162000D03*
X348700Y161700D03*
X351600Y164300D03*
X355400Y152900D03*
X350700Y155600D03*
X345900Y161700D03*
X342188Y183361D03*
X347200Y174300D03*
X344165Y169466D03*
X352200Y171800D03*
X347500Y169500D03*
X351600Y169600D03*
X353302Y182993D03*
X342233Y185639D03*
X356900Y186100D03*
X349600Y194800D03*
X342339Y192225D03*
X342342Y190024D03*
X349100Y191900D03*
X353625Y195045D03*
Y192045D03*
X356600Y195700D03*
X356700Y193300D03*
X345503Y193474D03*
X345500Y190500D03*
X349100Y189700D03*
X353342Y186124D03*
X345500Y184500D03*
X345631Y187420D03*
X353594Y210707D03*
X347593Y210277D03*
X353385Y212898D03*
X343242Y213690D03*
X347664Y212476D03*
X343198Y215910D03*
X371900Y85400D03*
X364800Y91200D03*
X368600Y90700D03*
X361200Y90200D03*
X371950Y92500D03*
X364874Y98250D03*
X362803Y106035D03*
X357900Y99200D03*
X368600Y97500D03*
X357721Y91779D03*
X361200Y97500D03*
X365316Y108130D03*
X372700Y119663D03*
X370100Y119563D03*
X370000Y116563D03*
X369997Y113706D03*
X359942Y110924D03*
X365721Y115528D03*
X358000Y115500D03*
X366400Y112200D03*
X364600Y137063D03*
X367221Y125428D03*
X370000Y122563D03*
X372821Y125628D03*
X370121Y125528D03*
X367321Y122528D03*
X368026Y137118D03*
X364700Y134000D03*
X367992Y133982D03*
X367121Y128628D03*
X362111Y130128D03*
X358500Y137000D03*
X371176Y136890D03*
X368000Y146500D03*
X361700Y143300D03*
X364886Y140268D03*
X368026D03*
Y143418D03*
X364621Y143328D03*
X361726Y140268D03*
X361700Y146549D03*
X361500Y149500D03*
X364700Y152713D03*
X368100Y165300D03*
X364600D03*
X367950Y159200D03*
X371157Y162320D03*
X371176Y158940D03*
X358477Y159300D03*
X361600Y159250D03*
X368100Y162200D03*
X358500Y155700D03*
X371100Y168700D03*
X361500Y175000D03*
Y168500D03*
X368000D03*
X361200Y178500D03*
X364792Y188743D03*
X364600Y186138D03*
X364895Y190941D03*
X369106Y191903D03*
X369200Y189100D03*
X361257Y193524D03*
Y190700D03*
X364947Y193141D03*
X372700Y213700D03*
X369450Y212040D03*
X358498Y210220D03*
X358382Y212427D03*
X372800Y221600D03*
X369580Y218800D03*
X357966Y217516D03*
X359827Y216341D03*
X383350Y83350D03*
X383450Y90500D03*
X387200D03*
X387100Y83500D03*
X375800D03*
Y90500D03*
X379500Y83302D03*
Y90600D03*
X381600Y119900D03*
X381900Y113000D03*
X382596Y108600D03*
X385600Y116500D03*
X385200Y113137D03*
X385721Y119528D03*
X381550Y117400D03*
X377800Y112063D03*
X377818Y115008D03*
X386561Y108812D03*
X377713Y121061D03*
X385479Y125569D03*
X381500Y123200D03*
X381600Y126427D03*
X385523Y122532D03*
X385750Y128517D03*
X386708Y137118D03*
X383567Y137096D03*
X377800Y124163D03*
X380475Y137016D03*
X380400Y133928D03*
X380443Y130102D03*
X374200Y136994D03*
X387000Y143280D03*
X380398Y146568D03*
X383548D03*
X380398Y143418D03*
X383395Y143306D03*
X374200Y140144D03*
Y143294D03*
X380400Y152700D03*
X383575Y149603D03*
X380522Y149564D03*
X377476Y149688D03*
X374200Y149494D03*
X374100Y159150D03*
X386800Y165300D03*
X380398Y165240D03*
X383781Y165235D03*
X386777Y162155D03*
X387000Y155850D03*
X380500Y162025D03*
X383700Y162199D03*
X383500Y159000D03*
X374300Y155800D03*
X377500Y165240D03*
Y156000D03*
X384740Y180080D03*
X381720Y180220D03*
X381800Y183300D03*
X380540Y177370D03*
X380500Y168500D03*
X383693Y171424D03*
X383548Y168390D03*
X386600Y174900D03*
X380477Y171605D03*
X376830Y175640D03*
X376800Y178600D03*
X376742Y181524D03*
X381460Y195610D03*
X384390Y196470D03*
X381140Y187960D03*
X381280Y191550D03*
X384708Y188910D03*
X384600Y186100D03*
X373922Y193103D03*
X374000Y190350D03*
X379750Y213500D03*
X376300Y211000D03*
X382600Y222600D03*
X382750Y229000D03*
X379700Y219200D03*
X385947Y226500D03*
X385900Y218400D03*
X376300Y216200D03*
X390700Y89300D03*
X403726Y83826D03*
X403700Y90200D03*
X397300Y89168D03*
X400400Y92200D03*
Y98500D03*
X390750Y96500D03*
X394100Y91400D03*
Y99000D03*
X397100Y96600D03*
X397300Y93100D03*
X392382Y102149D03*
X390650Y93000D03*
X394100Y94900D03*
X400400Y95000D03*
X393331Y118043D03*
X393351Y115107D03*
X397650Y115500D03*
X401749Y112418D03*
X401159Y119636D03*
X401353Y116562D03*
X396276Y120948D03*
X396251Y117999D03*
X396600Y112463D03*
X390683Y108042D03*
X400700Y108800D03*
X389700Y112363D03*
X398500Y125604D03*
X398512Y122815D03*
X401500Y125600D03*
X393482Y123982D03*
X396700Y128000D03*
X389914Y124536D03*
X399452Y133964D03*
X389380Y130100D03*
X390100Y127600D03*
X390205Y133858D03*
X389848Y137118D03*
X393000Y152663D03*
X402900Y149663D03*
X389721Y143320D03*
X393000Y140268D03*
X389848Y146568D03*
X393204Y146436D03*
X403080Y146931D03*
X399198Y146468D03*
X396192Y146444D03*
X392998Y149718D03*
X399198Y149618D03*
X396182Y149674D03*
X396200Y152763D03*
X396300Y162100D03*
X399300Y152863D03*
Y155963D03*
X392998Y165240D03*
X393028Y162059D03*
X393198Y158940D03*
X403078Y152922D03*
X402373Y155952D03*
X399298Y162090D03*
X402505Y159133D03*
X396148Y158940D03*
X399298D03*
X392599Y181686D03*
X400252Y182966D03*
X403600Y182400D03*
Y180200D03*
X402540Y171760D03*
X402600Y174611D03*
X395573Y175400D03*
X396000Y179000D03*
X397100Y181000D03*
X400301Y186099D03*
X397805Y192061D03*
X392600Y190600D03*
X396200Y194700D03*
X392624Y184537D03*
X389500Y193600D03*
X397307Y186607D03*
X395600Y184100D03*
Y190300D03*
X392700Y193563D03*
X403022Y192094D03*
X402967Y195005D03*
X389484Y190442D03*
X389300Y187700D03*
X392100Y213700D03*
X395700Y213600D03*
X400400Y209400D03*
X398500Y208000D03*
X389100Y224000D03*
X399700Y225000D03*
Y216400D03*
X395600Y224400D03*
X395700Y217000D03*
X391950Y220800D03*
X389200Y227400D03*
X392000Y217200D03*
X395700Y220600D03*
X399800D03*
X389150Y230300D03*
X407500Y84000D03*
X407400Y91000D03*
X411300Y85600D03*
X414722Y90250D03*
X414300Y85600D03*
X403800Y87000D03*
X407400Y87400D03*
X411000Y88900D03*
X418300Y91300D03*
X418400Y98150D03*
X411000Y92100D03*
X414622Y98000D03*
X414672Y94500D03*
X417800Y100400D03*
X412650Y100197D03*
X418300Y94800D03*
X407550Y100196D03*
X404529Y118507D03*
X405900Y121700D03*
X409110Y114910D03*
X405200Y115343D03*
X412462Y115713D03*
X409196Y118195D03*
X416904Y119591D03*
X413100Y121800D03*
X404900Y124600D03*
X416000Y135983D03*
X415000Y131400D03*
X408956Y130064D03*
X418500Y128200D03*
X415100Y127900D03*
X406200Y127400D03*
X416851Y122600D03*
X412462Y126300D03*
X417753Y131322D03*
X405500Y131063D03*
X414900Y147000D03*
X417900Y146900D03*
X408800Y147000D03*
X411900Y146800D03*
X413300Y139100D03*
X413400Y142700D03*
X418000Y142500D03*
X406000Y150200D03*
X407500Y152100D03*
X410400Y152000D03*
X418439Y167118D03*
X414800Y162600D03*
X411800Y162700D03*
X414572Y165913D03*
X411356Y165732D03*
X407500Y157600D03*
X412900Y157800D03*
X407400Y154863D03*
X406100Y159500D03*
X415100Y158100D03*
X410272Y154794D03*
X416400Y155000D03*
X408600Y159600D03*
X411600D03*
X409300Y167163D03*
X404558Y154835D03*
X407100Y167429D03*
X418600Y182800D03*
X414960Y178130D03*
X414950Y181460D03*
X411260Y178090D03*
X411553Y181222D03*
X416400Y170300D03*
X413265Y170423D03*
X410620Y173300D03*
X408158Y178666D03*
X417900Y178363D03*
X415992Y189254D03*
Y186205D03*
X419097Y189563D03*
X416500Y195563D03*
X408242Y184624D03*
X405231Y184976D03*
X408200Y190500D03*
X408100Y193600D03*
X412500Y197300D03*
X405000Y190700D03*
X412100Y190400D03*
X411342Y185024D03*
X405800Y196700D03*
X412200Y192600D03*
X416900Y200100D03*
X416353Y207249D03*
X408200Y226900D03*
X408100Y220500D03*
X404400Y228600D03*
Y222300D03*
X415600Y222700D03*
X415800Y215900D03*
X412050Y225100D03*
X412100Y218400D03*
X408200Y223800D03*
X412000Y222000D03*
X415700Y219200D03*
X404400Y225300D03*
X422078Y97678D03*
X422000Y91300D03*
X427560Y104770D03*
X429105Y106337D03*
X429500Y93800D03*
X434021Y100128D03*
X422050Y94800D03*
X428100Y120000D03*
X424900Y121213D03*
X420600Y118300D03*
X420672Y120600D03*
X422042Y115224D03*
X424700Y115000D03*
X427900Y114300D03*
X428100Y116500D03*
X430302Y112098D03*
X419596Y113463D03*
X428255Y126236D03*
X425000Y135350D03*
X419500Y136400D03*
X430100Y131500D03*
X431700Y128300D03*
X423500Y128200D03*
X427000Y128050D03*
X423900Y131500D03*
X420942Y131324D03*
X431504Y126061D03*
X424982Y126500D03*
X434700Y131800D03*
X426982Y131334D03*
X427600Y143841D03*
X421500Y142400D03*
X426900Y147100D03*
X431100Y145500D03*
X424856Y142270D03*
X422400Y139000D03*
X420861Y149687D03*
Y146923D03*
X430694Y142275D03*
X428390Y139059D03*
X423945Y165221D03*
X421710Y167230D03*
X431130Y166660D03*
X428238Y167709D03*
X420804Y162659D03*
X420900Y160037D03*
X425500Y154737D03*
X428400D03*
X434500Y160037D03*
X430360Y181350D03*
X430340Y177620D03*
X423642Y181374D03*
X426970Y178310D03*
X425400Y170240D03*
X428500Y173120D03*
X422337Y170575D03*
X425427Y173113D03*
X419453Y173187D03*
X420922Y178117D03*
X423842Y178274D03*
X428431Y170264D03*
X432100Y190400D03*
X429100Y189696D03*
X426173Y190784D03*
X428830Y195379D03*
X422152Y189600D03*
X420800Y193100D03*
X421171Y196496D03*
X431270Y193425D03*
X425500Y186045D03*
X429933Y197283D03*
X420975Y211300D03*
X427900Y202800D03*
X424832Y200174D03*
X421811Y202603D03*
X421253Y199822D03*
X425642Y209524D03*
X419550Y222700D03*
X419600Y216200D03*
Y219200D03*
X444578Y106201D03*
X442378Y106198D03*
X440178Y106200D03*
X437400Y121600D03*
X442842Y120824D03*
X438700Y112900D03*
X438500Y116400D03*
X439400Y120100D03*
X434960Y114529D03*
X444242Y124324D03*
X435442Y124024D03*
X437800Y128100D03*
X434700Y128200D03*
X443400Y148900D03*
X437472Y152501D03*
X434834Y163817D03*
X439600Y153800D03*
X435105Y181207D03*
X438742Y197224D03*
X435642Y194824D03*
X437921Y192956D03*
X445000Y194500D03*
X443100Y195900D03*
X443000Y192700D03*
X435453Y185397D03*
X436957Y209867D03*
X459800Y118800D03*
X453000Y118700D03*
X456200Y118900D03*
X459700Y129900D03*
X452200Y129800D03*
X463100Y133700D03*
X456000Y133500D03*
X460100Y123100D03*
X453000Y123300D03*
X463200Y126200D03*
X456500Y126100D03*
X461200Y167400D03*
X454200D03*
X464300Y181800D03*
X458000Y171100D03*
X451000D03*
X460000Y174900D03*
X453000D03*
X457400Y197000D03*
X450400D03*
X462500Y189000D03*
X460400Y193300D03*
X453400D03*
X456900D03*
X453900Y197000D03*
X459500Y200700D03*
X452500D03*
X456000D03*
X473900Y178200D03*
X466900D03*
X471300Y181800D03*
X467800D03*
X473100Y185500D03*
X466000D03*
X469500Y189000D03*
X469600Y185500D03*
X466000Y189000D03*
X504000Y12507D03*
X508700Y14607D03*
X511589Y30295D03*
X507839Y30362D03*
X506496Y272500D03*
X523453Y12360D03*
X511800Y12507D03*
X520700Y14807D03*
X518769Y22907D03*
X515484D03*
X525753Y30893D03*
X522733Y32832D03*
X511640Y255956D03*
X514137Y256089D03*
X522908Y255117D03*
X526715Y254700D03*
X511736Y273001D03*
X514900Y271350D03*
X522992Y270700D03*
X525845Y272863D03*
X517846Y262489D03*
X521131D03*
X528525Y12549D03*
X542100Y15107D03*
X530700Y15407D03*
X536485Y22907D03*
X533200D03*
X542407Y30882D03*
X532350Y30807D03*
X529120Y32575D03*
X530015Y255000D03*
X531775Y252231D03*
X541005Y254800D03*
X540900Y252300D03*
X530900Y273000D03*
X534100Y270700D03*
X541500Y270900D03*
X535562Y262489D03*
X538847D03*
X550000Y12507D03*
X544860Y12407D03*
X552800Y14807D03*
X557745Y22907D03*
X554460D03*
X553079Y30712D03*
X549500Y31607D03*
X545928Y31047D03*
X544800Y255100D03*
X550200Y255500D03*
X551000Y252056D03*
X552800Y255300D03*
X545500Y252600D03*
X553485Y252332D03*
X544292Y273128D03*
X548800Y271000D03*
X551937Y272789D03*
X555641Y262489D03*
X554500Y264900D03*
X568555Y12407D03*
X561200Y12507D03*
X571600Y14207D03*
X564400Y14307D03*
X570852Y33204D03*
X569800Y29807D03*
X565091Y30815D03*
X561456Y30902D03*
X561419Y254850D03*
X565054Y254773D03*
X568327Y253348D03*
X571867Y254685D03*
X560555Y252503D03*
X563376Y256627D03*
X566151Y252115D03*
X572150Y252200D03*
X560600Y270300D03*
X564100Y271100D03*
X567800Y270500D03*
X570200Y273100D03*
X558926Y262489D03*
X570200Y269700D03*
X559600Y272900D03*
X572155Y264900D03*
X565700Y273050D03*
X559700Y264900D03*
X572700Y273100D03*
X587940Y12417D03*
X582655Y12407D03*
X579800Y14807D03*
X577824Y22907D03*
X574539D03*
X583700Y28207D03*
X585179Y30867D03*
X581450Y30707D03*
X579100Y33207D03*
X585550Y33340D03*
X587700Y255300D03*
X579205Y254850D03*
X582200Y252206D03*
X587642D03*
X582300Y254900D03*
X578800Y252200D03*
X580200Y273000D03*
X582600Y270300D03*
X588036Y273089D03*
X588400Y270300D03*
X573357Y262489D03*
X576642D03*
X577450Y264900D03*
X580107Y270501D03*
X577636Y272947D03*
X594600Y6707D03*
X600896Y12407D03*
X601704Y22907D03*
X601000Y20507D03*
X594400Y36207D03*
X589300Y33007D03*
X590500Y30507D03*
X594200Y33607D03*
X600360Y33287D03*
X594600Y260000D03*
X591300Y255010D03*
X590837Y259889D03*
X598398Y260199D03*
X591342Y252206D03*
X594500Y265200D03*
X591500Y270100D03*
X591536Y273000D03*
X590700Y264833D03*
X598300Y265400D03*
X610952Y12307D03*
X616600D03*
X605700Y12407D03*
X615852Y19807D03*
X615907Y24856D03*
X607300Y14507D03*
X616707Y15616D03*
X604989Y22907D03*
X610800Y14807D03*
X605728Y20518D03*
X612000Y17407D03*
X610944Y33333D03*
X607800Y30407D03*
X618900Y33290D03*
X615103Y30690D03*
X610500Y30507D03*
X607544Y33340D03*
X619382Y260089D03*
X615532Y259700D03*
X611706Y259387D03*
X606700Y255600D03*
X604074Y254394D03*
X609500Y254900D03*
X609937Y252106D03*
X615537Y264789D03*
X619100Y265300D03*
X611536Y264385D03*
X609896Y272889D03*
X608996Y270206D03*
X605100Y270100D03*
X605065Y272967D03*
X623532Y20007D03*
X623555Y25107D03*
X619607Y19807D03*
X627255Y25107D03*
X627231Y19907D03*
X630955Y25207D03*
X631000Y20107D03*
X634555Y25307D03*
X634757Y20207D03*
X619730Y24864D03*
X630432Y260100D03*
X626682Y260300D03*
X622933Y260189D03*
X634207Y260300D03*
X630455Y265400D03*
X634280Y265332D03*
X626651Y265489D03*
X622899Y265189D03*
X644193Y12907D03*
X648800Y12707D03*
X638400Y20607D03*
X638290Y25674D03*
X642246Y25807D03*
X642451Y20707D03*
X645300Y15507D03*
X648400Y15490D03*
X647000Y29607D03*
X649550Y30807D03*
X643700Y33290D03*
X644100Y30307D03*
X638032Y260342D03*
X642802Y252186D03*
X645920Y254130D03*
X635043Y252106D03*
X638900Y254809D03*
X643020Y254710D03*
X647800Y252300D03*
X638090Y265340D03*
X642937Y273089D03*
X646360Y271530D03*
X637288Y270100D03*
X637337Y272944D03*
X648948Y262489D03*
X644090Y270420D03*
X648200Y265300D03*
X644550Y267170D03*
X648291Y273140D03*
X662359Y12379D03*
X659400Y25907D03*
Y20474D03*
X662192Y14874D03*
X663202Y25973D03*
X655602Y25223D03*
X663200Y20956D03*
X655700Y20225D03*
X662503Y33207D03*
X657900Y30690D03*
X664678Y30307D03*
X661708Y30699D03*
X659437Y246389D03*
X665500Y252189D03*
X653600Y252130D03*
X659500Y274000D03*
X665100Y272700D03*
X652233Y262489D03*
X653000Y264900D03*
X653041Y272989D03*
X671290Y12457D03*
X665901Y12307D03*
X675990Y12357D03*
X674320Y14219D03*
X666175Y14807D03*
X680580Y22807D03*
X677295D03*
X676600Y20307D03*
X671500Y15007D03*
X674400Y31307D03*
X671295Y33190D03*
X671900Y30707D03*
X675970Y33267D03*
X670200Y254700D03*
X673770Y254752D03*
X669700Y270900D03*
X672800Y272700D03*
X676113Y262489D03*
X679398D03*
X690102Y12502D03*
X684760Y12256D03*
X687602Y12439D03*
X694200Y13507D03*
X681280Y12457D03*
X692200Y15357D03*
X682013Y14848D03*
X695029Y22853D03*
X684500Y15507D03*
X689595Y27883D03*
X685400Y28307D03*
X681700Y20507D03*
X694205Y20302D03*
X693300Y30607D03*
X689624Y30383D03*
X685700Y30807D03*
X681900Y30907D03*
X693700Y33107D03*
X681280Y33340D03*
X687900Y33327D03*
X682800Y254900D03*
X685382Y252200D03*
X688800Y254600D03*
X692250Y255700D03*
X682481Y270700D03*
X685100Y273100D03*
X689700Y270800D03*
X692537Y272989D03*
X696192Y262489D03*
X709000Y12407D03*
X702000Y12607D03*
X699503Y12482D03*
X706360Y12397D03*
X705031Y14515D03*
X698277Y22855D03*
X705604Y16949D03*
X710813Y28796D03*
X699104Y20495D03*
X708900Y30407D03*
X704430Y33313D03*
X701800Y30807D03*
X707157Y33333D03*
X700940Y33340D03*
X701649Y255049D03*
X704178Y252189D03*
X707800Y255000D03*
X711400Y255072D03*
X701300Y270777D03*
X704277Y272989D03*
X709400Y272600D03*
X699477Y262489D03*
X723586Y14080D03*
X712182Y14124D03*
X714000Y12407D03*
X719110Y12347D03*
X725530Y12507D03*
X720100Y14707D03*
X718375Y22907D03*
X715090D03*
X714100Y20607D03*
X719220Y20553D03*
X727000Y30407D03*
X723500Y29907D03*
X721747Y32954D03*
X712400Y30807D03*
X721074Y30514D03*
X718350Y33107D03*
X712450Y33340D03*
X725653Y32654D03*
X721500Y255000D03*
X724374Y254515D03*
X712200Y270500D03*
X722400Y270800D03*
X725300Y272800D03*
X717452Y262489D03*
X720737D03*
X715900Y270000D03*
X742200Y12407D03*
X728010Y12857D03*
X737300Y12307D03*
X732110Y12267D03*
X739000Y14407D03*
X731169Y14584D03*
X736091Y23607D03*
X732806D03*
X728500Y15507D03*
X742100Y28107D03*
X732000Y20307D03*
X736748D03*
X728500Y27907D03*
X742100Y33007D03*
X740200Y29907D03*
X730500D03*
X733474Y33340D03*
X738487Y33094D03*
X730400Y255400D03*
X732200Y252200D03*
X741560Y255000D03*
X730400Y272850D03*
X732740Y270200D03*
X741200Y270500D03*
X735168Y262489D03*
X738453D03*
X745100Y12256D03*
X744900Y20500D03*
X745000Y23000D03*
X744800Y33007D03*
X747441D03*
X744437Y252189D03*
X744200Y272600D03*
X753000Y272100D03*
G54D17*
X42717Y191732D03*
G54D19*
X144000Y67875D03*
Y147125D03*
X276811Y263386D03*
X296811D03*
X457913Y45276D03*
X477913D03*
G54D14*
X13000Y137000D03*
Y141500D03*
X13100Y150600D03*
X13000Y146000D03*
X45500Y118000D03*
X76200Y187200D03*
X86500Y177500D03*
X90700Y177050D03*
X122250Y228750D03*
Y233000D03*
Y237300D03*
Y241500D03*
X133941Y208863D03*
X131003Y205766D03*
X138100Y208100D03*
X136500Y272500D03*
X158700Y213800D03*
X309100Y206800D03*
X315400Y110800D03*
X311600D03*
X322691Y136023D03*
X323550Y142104D03*
X319401Y149354D03*
X317698Y152311D03*
X315384Y166733D03*
X324953Y161722D03*
X323165Y171937D03*
X324436Y175705D03*
X326399Y169401D03*
X319942Y180524D03*
X320029Y184300D03*
X318700Y207800D03*
X311600Y207600D03*
X328000Y97100D03*
X334850Y96900D03*
X335500Y91600D03*
X332600Y101400D03*
X333551Y115090D03*
X333416Y108899D03*
X341309Y135651D03*
X329693Y134428D03*
X331290Y125810D03*
X330870Y130540D03*
X336190Y141970D03*
X330796Y146221D03*
X333742Y161624D03*
X332185Y153806D03*
X334470Y164760D03*
X335400Y169600D03*
X333842Y177224D03*
X332300Y173900D03*
X339875Y177303D03*
X334715Y180900D03*
X329028Y199931D03*
X351500Y136000D03*
X343000Y124000D03*
X357300Y128600D03*
X355400Y137100D03*
X354300Y128600D03*
X342880Y146180D03*
X355342Y143424D03*
X348743Y149100D03*
X342716Y161593D03*
X345562Y178700D03*
X349751Y187241D03*
X356800Y191000D03*
X361141Y104099D03*
X362111Y127142D03*
X362120Y124153D03*
X359421Y127128D03*
Y124008D03*
X359300Y130000D03*
X368026Y149718D03*
X364600Y174800D03*
X364607Y177103D03*
X372600Y181400D03*
X361400Y187600D03*
X368455Y196455D03*
X371299Y196008D03*
X361300Y184500D03*
X369009Y186191D03*
X359750Y208390D03*
X359910Y214100D03*
X371100Y199500D03*
X365250Y208600D03*
X369580Y215400D03*
X384650Y183170D03*
X376800Y193500D03*
X376900Y196600D03*
X380510Y185500D03*
X384684Y191950D03*
X376300Y213700D03*
X382471Y199843D03*
X385900Y222600D03*
X382700Y226000D03*
X379700Y216500D03*
X372950Y217400D03*
X393653Y121122D03*
X401500Y122600D03*
X401256Y128755D03*
X397800Y130000D03*
X400352Y180171D03*
X402962Y189014D03*
X397728Y189053D03*
X409110Y120910D03*
X412100Y135600D03*
X412600Y124100D03*
X404400Y128900D03*
X415700Y143100D03*
X410302Y141864D03*
X406042Y147025D03*
X415100Y149800D03*
X407399Y142561D03*
X408837Y149809D03*
X413314Y154908D03*
X416315Y183219D03*
X412000Y187500D03*
X405102Y187874D03*
X422300Y126300D03*
X432542Y136898D03*
X423496Y144000D03*
X428363Y141756D03*
X426000Y167370D03*
X430542Y160753D03*
X430600Y164513D03*
X422363Y154700D03*
X423966Y190846D03*
X423800Y196500D03*
X433842Y197021D03*
X421848Y186550D03*
X426311Y204399D03*
X443443Y144757D03*
X437398Y146257D03*
X435004Y142110D03*
G54D23*
X305900Y121151D03*
X311200Y114800D03*
X311410Y118110D03*
X312000Y122600D03*
X312917Y133440D03*
X312829Y181940D03*
X345837Y199887D03*
G54D12*
X14000Y104500D03*
X14400Y98000D03*
X14000Y109500D03*
X14500Y198000D03*
X17301Y212401D03*
X4500Y228900D03*
X4600Y223100D03*
X17300Y218307D03*
X10000Y229500D03*
X16400Y224212D03*
X4500Y234800D03*
X4400Y245100D03*
X16118Y230118D03*
X10194Y243106D03*
X9500Y234200D03*
X16899Y241929D03*
X16300Y236023D03*
X4400Y256700D03*
X10190Y258510D03*
X10194Y254917D03*
X10190Y246699D03*
X16899Y247834D03*
Y253740D03*
Y259645D03*
X5000Y275000D03*
X12600Y266900D03*
X7600Y268100D03*
X16899Y265551D03*
X15300Y285800D03*
X4900Y285700D03*
X23400Y81550D03*
X25000Y77300D03*
X32800Y120400D03*
X25800Y120300D03*
X29200D03*
X30000Y196200D03*
X21900Y205400D03*
X31500Y207500D03*
X25200Y286000D03*
X40500Y127700D03*
X38500Y148000D03*
X48500D03*
X41000Y152300D03*
Y143300D03*
X46000D03*
Y152300D03*
X43500Y148000D03*
Y138500D03*
X48500D03*
X38500D03*
X45800Y158100D03*
X34800Y198800D03*
Y203700D03*
X37600Y212700D03*
Y207800D03*
X34500Y216000D03*
X40400Y217100D03*
X40700Y224000D03*
X40200Y238300D03*
Y231300D03*
Y245300D03*
X40500Y260000D03*
X40600Y252500D03*
X52500Y96500D03*
Y106500D03*
X57500Y96500D03*
X60000Y101500D03*
X50000D03*
X55000D03*
X57500Y106500D03*
X60000Y111300D03*
X50000D03*
X55000D03*
X50500Y160000D03*
X54700Y192200D03*
X52700Y184800D03*
X62800Y184300D03*
X57600Y214200D03*
X74000Y37642D03*
X66500D03*
X78300Y64300D03*
X72137Y210237D03*
X79500Y230000D03*
X78700Y259800D03*
X67600Y255800D03*
X66300Y259300D03*
X67000Y263200D03*
X82211Y37747D03*
X89862Y37849D03*
X89400Y58200D03*
X83600Y57600D03*
X95500Y93500D03*
X94000Y137500D03*
Y133000D03*
X84500Y230000D03*
X89500D03*
X84500Y225000D03*
Y235000D03*
X91400Y270300D03*
X98500Y37642D03*
X105794Y37692D03*
X104400Y57700D03*
X96800Y53300D03*
X99500Y91500D03*
Y96000D03*
X104000Y92000D03*
Y96500D03*
X105775Y137349D03*
X103175Y134050D03*
X98500Y137500D03*
X109000Y134050D03*
X98500Y133000D03*
X95700Y197200D03*
X99600Y225700D03*
X99328Y235370D03*
X109000Y231400D03*
X113605Y37665D03*
X121500Y37642D03*
X121400Y60100D03*
X114800Y60700D03*
X114500Y134050D03*
X120500Y139000D03*
X125000Y178000D03*
X119760Y191419D03*
X115760D03*
X123760D03*
X129336Y37652D03*
X137300Y37642D03*
X136400Y60600D03*
X130400D03*
X136500Y101523D03*
X136770Y113000D03*
X136500Y126300D03*
X132700Y158600D03*
X153088Y37653D03*
X145070Y37642D03*
X143700Y54503D03*
X154615Y54500D03*
X152811Y84300D03*
X157175Y115462D03*
X150670Y112100D03*
Y122300D03*
X150500Y183000D03*
X157000Y169194D03*
X168791Y37689D03*
X160898Y37704D03*
X169600Y53000D03*
X159957Y51932D03*
X167500Y68000D03*
X158105Y96775D03*
X171800Y126600D03*
X162900Y152200D03*
X167602Y160684D03*
X169800Y181448D03*
X165700Y203400D03*
X162000Y226000D03*
X167000D03*
Y221500D03*
X162000D03*
Y230500D03*
X167000D03*
X162000Y235000D03*
X176640Y37699D03*
X184500Y37700D03*
X185000Y51600D03*
X175758Y52879D03*
X184300Y78500D03*
X177200Y130575D03*
X187597Y133697D03*
X176400Y175700D03*
X185546Y192509D03*
X180546D03*
X175546D03*
X177500Y209500D03*
X176800Y241600D03*
X186500Y276500D03*
Y281000D03*
X192400Y37642D03*
X200300D03*
X191700Y52100D03*
X201500Y54500D03*
X196900Y68700D03*
X198500Y83800D03*
X193485Y83724D03*
X202500Y97000D03*
X188363Y116137D03*
X201252Y137766D03*
X192237Y147300D03*
X199900Y154200D03*
X200900Y177000D03*
X202800Y191400D03*
X196000Y186897D03*
X191400Y206100D03*
X203100Y252900D03*
X191100Y276600D03*
X190900Y280800D03*
X207600Y37642D03*
X216085Y37649D03*
X210900Y57600D03*
X213558Y98500D03*
X205689Y112879D03*
X205850Y118175D03*
X210100Y135800D03*
X213850Y179850D03*
X205920Y221550D03*
X211900Y253000D03*
X207500D03*
X212400Y281200D03*
X217000Y281000D03*
X212500Y277000D03*
X208000D03*
X223868Y37686D03*
X231780Y37691D03*
X229036Y83000D03*
X231562Y143827D03*
X231611Y138336D03*
X226452Y147300D03*
X233350Y180700D03*
X232225Y193275D03*
X233500Y258958D03*
X228000Y259000D03*
X239599Y37673D03*
X247500Y37642D03*
X238800Y45300D03*
X240200Y59275D03*
X247500Y60000D03*
X244463Y130655D03*
X242950Y155800D03*
X236477Y179357D03*
X239300Y196800D03*
X236861Y184967D03*
X248300Y213500D03*
X248000Y259000D03*
X238500D03*
X243000D03*
X261900Y44900D03*
X255000Y37642D03*
X263100Y37700D03*
X264700Y59400D03*
X256200Y59200D03*
X264189Y98252D03*
X257000Y213500D03*
X252700D03*
X252500Y259000D03*
X271000Y37800D03*
X278800Y37700D03*
X274000Y55800D03*
X268928Y112625D03*
X268895Y107350D03*
X268300Y141869D03*
X269772Y188274D03*
X274700Y222100D03*
X286900Y37800D03*
X294500Y37900D03*
X292500Y60500D03*
X284000Y55800D03*
X288700Y71100D03*
X292100D03*
X295300Y66200D03*
X285100Y129510D03*
X281500Y142100D03*
X295900Y154200D03*
X287700Y211900D03*
X295300Y238100D03*
X285000Y261700D03*
X310348Y37900D03*
X302600Y37800D03*
X302400Y59500D03*
X306100Y90600D03*
X311000Y141731D03*
X297250Y163700D03*
X311242Y158732D03*
X305290Y187836D03*
X301320Y191060D03*
X310500Y195600D03*
X308200D03*
X326096Y37900D03*
X318048Y37700D03*
X311598Y57522D03*
X322548Y58300D03*
X323882Y71643D03*
X318882D03*
X321300Y88200D03*
X325350Y114500D03*
X326313Y122380D03*
X311460Y172078D03*
X323800Y192150D03*
X323789Y188117D03*
X326500Y187900D03*
X311900Y188070D03*
X319500Y212100D03*
X315585Y207787D03*
X324100Y208000D03*
X325200Y221700D03*
X319400Y216200D03*
X313600Y237700D03*
X321400D03*
X322000Y264300D03*
X333700Y38000D03*
X328300Y58200D03*
X328882Y71643D03*
X330470Y112515D03*
X330910Y115010D03*
X338421Y153802D03*
X326831Y196119D03*
X337670Y213520D03*
X332974Y210874D03*
X339800Y207400D03*
X330200Y216800D03*
X336000Y219750D03*
X333036Y231910D03*
X327100Y237100D03*
X353100Y56151D03*
X353500Y71900D03*
X357000Y69500D03*
X349300Y83000D03*
X345100D03*
X354200Y76400D03*
X346600Y121100D03*
X355460Y149510D03*
X355413Y156050D03*
X351700Y167300D03*
X355300Y174600D03*
X350000Y177700D03*
X353321Y180128D03*
X350409Y199755D03*
X354700Y199900D03*
X363583Y37642D03*
X359800Y72700D03*
X362700Y69600D03*
X368721Y108528D03*
X367900Y152550D03*
X358342Y165324D03*
X358576Y162090D03*
X367906Y171458D03*
X364600Y171600D03*
X370900Y171700D03*
X361292Y181409D03*
X372400Y179100D03*
X369021Y180128D03*
X365800Y264900D03*
X362400D03*
X369300D03*
X375400Y37700D03*
X380000Y263461D03*
X383500D03*
X376500D03*
X393561Y127130D03*
X396148Y155790D03*
X393208D03*
X399298Y165240D03*
X395641Y188045D03*
X393000Y236200D03*
X397400Y239700D03*
X389500Y275300D03*
X416922Y116613D03*
X405990Y144251D03*
X409096Y143963D03*
X410100Y157700D03*
X408900Y162463D03*
X410408Y170261D03*
X405100Y178500D03*
X407552Y170424D03*
X405700Y246500D03*
X430500Y17000D03*
X427500Y112091D03*
X425200Y118823D03*
X430342Y119724D03*
X426900Y160040D03*
X419340Y170500D03*
X434482Y177021D03*
X428400Y185900D03*
X423900Y257500D03*
X444783Y28451D03*
X439276Y159645D03*
X443800Y246100D03*
X445300Y274400D03*
X451000Y257413D03*
X456300Y275300D03*
X474000Y9000D03*
X467200Y4400D03*
X480400Y154050D03*
X467100Y154200D03*
X477000Y154050D03*
X470100Y154200D03*
X473500Y154050D03*
X467700Y245500D03*
X481500Y8900D03*
X489600Y8800D03*
X483800Y154050D03*
X487200Y154100D03*
X497100Y8800D03*
X506800Y12907D03*
X508700Y17207D03*
X506500Y32807D03*
X514360Y12417D03*
X526000Y12507D03*
X519426Y12318D03*
X522311Y16720D03*
X514300Y20507D03*
X519623Y20457D03*
X522700Y30007D03*
X513005Y32412D03*
X519400Y33340D03*
X526700Y33207D03*
X524700Y119500D03*
X515000Y119270D03*
X524700Y145041D03*
X537964Y12317D03*
X532500Y13407D03*
X541114Y12307D03*
X528219Y15096D03*
X532472Y20515D03*
X537410Y20584D03*
X529000Y30007D03*
X541950Y33340D03*
X532542Y33307D03*
X537200Y33207D03*
X531000Y228350D03*
X547500Y12507D03*
X553720Y12297D03*
X550234Y14997D03*
X553797Y20496D03*
X549500Y29107D03*
X553250Y33207D03*
X547306Y33134D03*
X552100Y136000D03*
X557100D03*
X558448Y12407D03*
X566040Y12317D03*
X566000Y16507D03*
X572200Y28707D03*
X558500Y20507D03*
X573200Y19907D03*
X565470Y33287D03*
X573242Y32462D03*
X560635Y33264D03*
X572100Y136000D03*
X567100D03*
X562000Y127800D03*
X562100Y136000D03*
X562000Y144900D03*
X573470Y12347D03*
X578620Y12357D03*
X585280Y12267D03*
X578600Y20307D03*
X590000Y14007D03*
X594500Y4007D03*
X599300Y119270D03*
X588800Y145000D03*
X599200D03*
X598814Y240095D03*
X614700Y14107D03*
X615951Y22356D03*
X615044Y33190D03*
X618877Y30790D03*
X617700Y125500D03*
X615100Y238900D03*
X633500Y12406D03*
X624000D03*
X634757Y22707D03*
X623480Y22564D03*
X631007Y22707D03*
X619700Y22307D03*
X627257Y22407D03*
X624100Y33190D03*
X633449D03*
X623900Y239600D03*
X641745Y12367D03*
X645200Y27707D03*
X646800Y17607D03*
X642257Y23307D03*
X638507Y23183D03*
X650200Y33307D03*
X641900Y31507D03*
X646000Y46007D03*
X640000D03*
X639500Y136490D03*
X648500Y162600D03*
X657897Y12504D03*
X651316Y12360D03*
X664212Y16356D03*
X663300Y23454D03*
X662916Y28457D03*
X655592Y22723D03*
X659400Y23207D03*
X657900Y33190D03*
X654500Y46107D03*
X650726Y125724D03*
X664212Y147993D03*
X661600Y156700D03*
X654100Y221800D03*
X659811Y260757D03*
X657500Y258400D03*
X661308Y263698D03*
X655500Y270500D03*
X657787Y264179D03*
X656000Y261400D03*
X655523Y266616D03*
X658667Y267622D03*
X669600Y17907D03*
X678400Y114500D03*
X668411Y148089D03*
X678500Y141500D03*
X667061Y175239D03*
X676200Y181600D03*
X693500Y148000D03*
X690000Y159000D03*
X694500D03*
X684700Y179800D03*
X694600Y229800D03*
X700089Y91411D03*
X701600Y104900D03*
X701400Y98400D03*
X698000Y181500D03*
X704700Y183800D03*
X710200Y201700D03*
X721200Y65100D03*
X715700Y124200D03*
X727187Y140000D03*
X717000Y187500D03*
X715500Y205837D03*
X738500Y90000D03*
X739500Y114900D03*
X741104Y133763D03*
X736900Y162300D03*
X729500D03*
X733400D03*
X737000Y188315D03*
X734000Y205000D03*
X753500Y24007D03*
Y20007D03*
Y28507D03*
X755500Y16000D03*
X756000Y106000D03*
X758176Y135024D03*
X745104Y129763D03*
X749104Y133763D03*
X745104D03*
X752191Y146613D03*
X745104Y137763D03*
X747000Y162000D03*
X750500D03*
X746000Y182300D03*
X767500Y24007D03*
X760500Y29000D03*
X761000Y16007D03*
X767500Y28507D03*
Y19507D03*
X764200Y44200D03*
X767500Y33207D03*
X764500Y54000D03*
X764300Y49200D03*
X769500Y50000D03*
X761000Y58500D03*
X764500Y84800D03*
X760400Y88700D03*
X768100Y89000D03*
X761300Y95700D03*
X768500Y114000D03*
X763600Y168000D03*
X764000Y188000D03*
Y197500D03*
Y192810D03*
Y202310D03*
X769500Y234500D03*
X769400Y252700D03*
X785500Y8000D03*
X784000Y31000D03*
X781500Y51000D03*
X777000Y93100D03*
X774300Y102500D03*
X778500D03*
Y107000D03*
X774300D03*
X783000Y113000D03*
Y118500D03*
Y123000D03*
X779000Y142000D03*
X788515Y144060D03*
X784515D03*
X796515D03*
X792515D03*
X800515D03*
Y148060D03*
X796515D03*
X792515D03*
X810500Y196500D03*
Y192300D03*
X809200Y209500D03*
Y213700D03*
Y218400D03*
X809100Y228600D03*
Y224400D03*
X808700Y238300D03*
Y234100D03*
Y242900D03*
X809500Y251500D03*
Y257000D03*
X808700Y247100D03*
X809700Y285900D03*
X820500Y6500D03*
X821900Y273100D03*
X821600Y285500D03*
G54D29*
X350197Y231103D03*
G54D11*
X11500Y68500D03*
X12000Y279000D03*
X816000Y280000D03*
G54D16*
X45669Y77185D03*
Y172460D03*
G54D21*
X200197Y282677D03*
X298622D03*
G54D10*
X-19686Y15748D03*
Y573228D03*
X846455Y15748D03*
Y573228D03*
G54D25*
X315613Y100850D03*
X339280Y127380D03*
X431188Y116105D03*
G54D26*
X325300Y112300D03*
X319252Y140949D03*
X324200Y157800D03*
X311417Y153821D03*
X341300Y169600D03*
X332100Y185600D03*
X338000Y185700D03*
X335000Y185500D03*
X332800Y187700D03*
X386853Y149640D03*
X392998Y133968D03*
X396148D03*
X396321Y136987D03*
X402561Y137000D03*
X399298Y137118D03*
X392998D03*
X402400Y140163D03*
X403132Y144374D03*
X396148Y140268D03*
X399298D03*
X390025Y174672D03*
X431620Y154620D03*
X421697Y174049D03*
X439275Y124197D03*
X456200Y129600D03*
X459700Y133600D03*
X459800Y126200D03*
X456500Y123000D03*
X457700Y167400D03*
X456500Y174900D03*
X454500Y171100D03*
X470400Y178200D03*
G54D27*
X322010Y118573D03*
X323007Y127672D03*
X338048Y196250D03*
X342029Y196427D03*
X349600Y126700D03*
X342760Y187810D03*
X371900Y89000D03*
X368600Y94100D03*
X365000Y94700D03*
X357721Y95100D03*
X360900Y94200D03*
X375800Y87000D03*
X383450Y86900D03*
X387200D03*
X379500D03*
X379526Y106396D03*
X381950Y100950D03*
X386777Y159005D03*
X399300Y168400D03*
X393077Y168455D03*
X399385Y171686D03*
X396225D03*
X393085D03*
Y174836D03*
X392596Y187541D03*
X417785Y162622D03*
X406000Y162663D03*
X412500Y194900D03*
X418800Y196700D03*
X416139Y192007D03*
X426800Y97850D03*
X419499Y139064D03*
X423910Y175700D03*
X432712Y172469D03*
X435453Y167560D03*
X507817Y252248D03*
X511200Y258900D03*
X509244Y272796D03*
X516600Y252200D03*
X521800Y252875D03*
X513776Y258563D03*
X516727Y273122D03*
X521790Y273140D03*
X517100Y265100D03*
X521987D03*
X532900Y255300D03*
X535098Y252600D03*
X527400Y252100D03*
X529300Y271000D03*
X528330Y273140D03*
X539937Y272989D03*
X539505Y265100D03*
X534905Y273097D03*
X534700Y265100D03*
X546200Y271000D03*
X546900Y273100D03*
X554434Y272914D03*
X603187Y252056D03*
X589500Y257100D03*
X589900Y268133D03*
X602450Y272900D03*
X598418Y262699D03*
X590322Y262361D03*
X594559Y262559D03*
X595386Y272932D03*
X608700Y257300D03*
X611845Y253723D03*
X611593Y261885D03*
X606200Y267800D03*
X615430Y262213D03*
X612393Y273026D03*
X619180Y262689D03*
X629937Y272990D03*
X630457Y262832D03*
X626680Y262989D03*
X634280Y262832D03*
X620437Y272990D03*
X622930Y262689D03*
X635197Y254602D03*
X638893Y252206D03*
X637987Y262842D03*
X639500Y268800D03*
X665300Y254700D03*
X661200Y248500D03*
X664500Y270000D03*
X661600Y272300D03*
X669930Y252150D03*
X674636Y252406D03*
X680600Y265000D03*
X675400D03*
X668000Y272890D03*
X680400Y273100D03*
X675400D03*
X690000Y256800D03*
X685390Y254900D03*
X688720Y252090D03*
X693860Y252210D03*
X681900Y252500D03*
X691900Y269300D03*
X683100Y268000D03*
X695500Y265000D03*
Y273100D03*
X687682Y272889D03*
X704137Y254796D03*
X699800Y252230D03*
X701704Y257549D03*
X707490Y252310D03*
X706000Y270500D03*
X700200Y264900D03*
X700300Y273100D03*
X706900Y273000D03*
X712350Y252640D03*
X725950Y252573D03*
X721395Y252175D03*
X721600Y257500D03*
X716737Y252189D03*
X716795Y265000D03*
X721400D03*
X721395Y273100D03*
X713100Y273000D03*
X716737Y272989D03*
X730300Y257900D03*
X734937Y253100D03*
X739750Y252800D03*
X729860Y269810D03*
X734200Y265100D03*
X739111Y264962D03*
X739838Y272813D03*
X727800Y272800D03*
X734510Y273110D03*
X744100Y254800D03*
X749000Y252200D03*
X746737Y272889D03*
G54D28*
X320321Y130528D03*
X351950Y214800D03*
X346500Y208350D03*
X345500Y213000D03*
X353792Y208466D03*
X355860Y216690D03*
X345300Y216700D03*
X359222Y197700D03*
G54D30*
X384810Y208530D03*
X384644Y205994D03*
%LPC*%
G75*
G54D31*
G01X10636Y-27865D02*
G02I-12000J0D01*
G01X14636D02*
X-17364D01*
G01X5486D02*
G02I-6850J0D01*
G01X-1364Y-43865D02*
Y-11865D01*
G01X14636Y-43865D02*
Y-123865D01*
G01D02*
X1309236D01*
G01X14636Y-79365D02*
X1309236D01*
G01X14636Y-43865D02*
X1309236D01*
G01X521736D02*
Y-123865D01*
G01X659236Y-43865D02*
Y-123865D01*
G01X774236Y-43865D02*
Y-123865D01*
G01X941736Y-43865D02*
Y-123865D01*
G01X1111736Y-43865D02*
Y-123865D01*
G01X1309236Y-43865D02*
Y-123865D01*
G01X1341236Y-27865D02*
X1309236D01*
G01X1337236D02*
G02I-12000J0D01*
G01X1332086D02*
G02I-6850J0D01*
G01X1325236Y-43865D02*
Y-11865D01*
G54D32*
G01X70851Y-113865D02*
Y-96365D01*
G01X80021D02*
Y-113865D01*
G01Y-105115D02*
X70851D01*
G01X92936Y-113865D02*
X91626Y-113573D01*
X90316Y-112407D01*
X89442Y-110365D01*
X89006Y-108032D01*
X89442Y-105698D01*
X90316Y-103657D01*
X91626Y-102490D01*
X92936Y-102199D01*
X94246Y-102490D01*
X95556Y-103657D01*
X96429Y-105698D01*
X96648Y-108032D01*
X96429Y-110365D01*
X95556Y-112407D01*
X94246Y-113573D01*
X92936Y-113865D01*
G01X106724D02*
Y-102199D01*
G01Y-105115D02*
X107598Y-103657D01*
X108908Y-102490D01*
X110654Y-102199D01*
X112182Y-102490D01*
X113493Y-103657D01*
X114148Y-105698D01*
Y-113865D01*
G01X124661Y-105990D02*
X131648D01*
X130993Y-103948D01*
X129901Y-102782D01*
X128373Y-102199D01*
X126844Y-102490D01*
X125534Y-103365D01*
X124661Y-105407D01*
X124224Y-107157D01*
Y-108907D01*
X124661Y-110657D01*
X125753Y-112407D01*
X127063Y-113573D01*
X128591Y-113865D01*
X130119Y-113282D01*
X131648Y-111532D01*
G01X140851Y-119115D02*
X142161Y-119698D01*
X143908Y-119115D01*
X144999Y-117949D01*
X145873Y-116490D01*
X147182Y-111824D01*
X150021Y-102199D01*
G01X143034D02*
X147182Y-111824D01*
G01X182182Y-104532D02*
X183056Y-103657D01*
X183711Y-102199D01*
X184148Y-100156D01*
X183711Y-98407D01*
X182838Y-97240D01*
X181309Y-96365D01*
X175414D01*
Y-113865D01*
X182619D01*
X184148Y-112699D01*
X185021Y-110948D01*
X185458Y-108907D01*
X185021Y-106865D01*
X183711Y-105115D01*
X182182Y-104532D01*
X175414D01*
G01X201866Y-113865D02*
Y-102199D01*
G01Y-104240D02*
X200993Y-103074D01*
X199682Y-102490D01*
X198154Y-102199D01*
X196626Y-102782D01*
X195316Y-103948D01*
X194442Y-105698D01*
X194006Y-108032D01*
X194442Y-110365D01*
X195316Y-112115D01*
X196626Y-113282D01*
X198154Y-113865D01*
X199682Y-113573D01*
X200993Y-112699D01*
X201866Y-111532D01*
G01X219366Y-96365D02*
Y-113865D01*
G01Y-111241D02*
X218493Y-112699D01*
X217182Y-113573D01*
X215654Y-113865D01*
X213908Y-113282D01*
X212598Y-111824D01*
X211724Y-110074D01*
X211506Y-108032D01*
X211724Y-105990D01*
X212598Y-104240D01*
X213908Y-102782D01*
X215654Y-102199D01*
X217182Y-102490D01*
X218274Y-103074D01*
X219366Y-104240D01*
G01X229879Y-118240D02*
X231408Y-119407D01*
X233154Y-119698D01*
X234682Y-119407D01*
X235993Y-117949D01*
X236866Y-115907D01*
Y-102199D01*
G01Y-104532D02*
X235993Y-103365D01*
X234682Y-102490D01*
X233154Y-102199D01*
X231408Y-102782D01*
X230316Y-103948D01*
X229442Y-105990D01*
X229006Y-108032D01*
X229224Y-109782D01*
X230098Y-111824D01*
X231408Y-113282D01*
X233154Y-113865D01*
X234464Y-113573D01*
X235993Y-112407D01*
X236866Y-111241D01*
G01X247161Y-105990D02*
X254148D01*
X253493Y-103948D01*
X252401Y-102782D01*
X250873Y-102199D01*
X249344Y-102490D01*
X248034Y-103365D01*
X247161Y-105407D01*
X246724Y-107157D01*
Y-108907D01*
X247161Y-110657D01*
X248253Y-112407D01*
X249563Y-113573D01*
X251091Y-113865D01*
X252619Y-113282D01*
X254148Y-111532D01*
G01X264879Y-113865D02*
Y-102199D01*
G01Y-104532D02*
X265971Y-103365D01*
X267063Y-102490D01*
X268591Y-102199D01*
X269682Y-102490D01*
X270993Y-103365D01*
G01X298569Y-113865D02*
Y-96365D01*
X303809D01*
X305556Y-97240D01*
X306866Y-99282D01*
X307303Y-101615D01*
X306866Y-103948D01*
X305774Y-105698D01*
X303809Y-106574D01*
X298569D01*
G01X324366Y-113865D02*
Y-102199D01*
G01Y-104240D02*
X323493Y-103074D01*
X322182Y-102490D01*
X320654Y-102199D01*
X319126Y-102782D01*
X317816Y-103948D01*
X316942Y-105698D01*
X316506Y-108032D01*
X316942Y-110365D01*
X317816Y-112115D01*
X319126Y-113282D01*
X320654Y-113865D01*
X322182Y-113573D01*
X323493Y-112699D01*
X324366Y-111532D01*
G01X334224Y-113865D02*
Y-102199D01*
G01Y-105115D02*
X335098Y-103657D01*
X336408Y-102490D01*
X338154Y-102199D01*
X339682Y-102490D01*
X340993Y-103657D01*
X341648Y-105698D01*
Y-113865D01*
G01X355436Y-96365D02*
Y-113865D01*
G01X352379Y-102199D02*
X358493D01*
G01X369224Y-113865D02*
Y-96365D01*
G01Y-104823D02*
X370316Y-103365D01*
X371408Y-102490D01*
X373154Y-102199D01*
X374464Y-102490D01*
X375993Y-103657D01*
X376648Y-105407D01*
Y-113865D01*
G01X387161Y-105990D02*
X394148D01*
X393493Y-103948D01*
X392401Y-102782D01*
X390873Y-102199D01*
X389344Y-102490D01*
X388034Y-103365D01*
X387161Y-105407D01*
X386724Y-107157D01*
Y-108907D01*
X387161Y-110657D01*
X388253Y-112407D01*
X389563Y-113573D01*
X391091Y-113865D01*
X392619Y-113282D01*
X394148Y-111532D01*
G01X404879Y-113865D02*
Y-102199D01*
G01Y-104532D02*
X405971Y-103365D01*
X407063Y-102490D01*
X408591Y-102199D01*
X409682Y-102490D01*
X410993Y-103365D01*
G01X437259Y-113865D02*
Y-96365D01*
X442936Y-110948D01*
X448613Y-96365D01*
Y-113865D01*
G01X462182Y-104532D02*
X463056Y-103657D01*
X463711Y-102199D01*
X464148Y-100156D01*
X463711Y-98407D01*
X462838Y-97240D01*
X461309Y-96365D01*
X455414D01*
Y-113865D01*
X462619D01*
X464148Y-112699D01*
X465021Y-110948D01*
X465458Y-108907D01*
X465021Y-106865D01*
X463711Y-105115D01*
X462182Y-104532D01*
X455414D01*
G01X227259Y-68865D02*
Y-51365D01*
X232936Y-65948D01*
X238613Y-51365D01*
Y-68865D01*
G01X250436D02*
X249126Y-68573D01*
X247816Y-67407D01*
X246942Y-65365D01*
X246506Y-63032D01*
X246942Y-60698D01*
X247816Y-58657D01*
X249126Y-57490D01*
X250436Y-57199D01*
X251746Y-57490D01*
X253056Y-58657D01*
X253929Y-60698D01*
X254148Y-63032D01*
X253929Y-65365D01*
X253056Y-67407D01*
X251746Y-68573D01*
X250436Y-68865D01*
G01X271866Y-51365D02*
Y-68865D01*
G01Y-66241D02*
X270993Y-67699D01*
X269682Y-68573D01*
X268154Y-68865D01*
X266408Y-68282D01*
X265098Y-66824D01*
X264224Y-65074D01*
X264006Y-63032D01*
X264224Y-60990D01*
X265098Y-59240D01*
X266408Y-57782D01*
X268154Y-57199D01*
X269682Y-57490D01*
X270774Y-58074D01*
X271866Y-59240D01*
G01X282161Y-60990D02*
X289148D01*
X288493Y-58948D01*
X287401Y-57782D01*
X285873Y-57199D01*
X284344Y-57490D01*
X283034Y-58365D01*
X282161Y-60407D01*
X281724Y-62157D01*
Y-63907D01*
X282161Y-65657D01*
X283253Y-67407D01*
X284563Y-68573D01*
X286091Y-68865D01*
X287619Y-68282D01*
X289148Y-66532D01*
G01X302936Y-68865D02*
Y-51365D01*
G01X542319Y-68865D02*
Y-51365D01*
X547559D01*
X549306Y-52240D01*
X550616Y-54282D01*
X551053Y-56615D01*
X550616Y-58948D01*
X549524Y-60698D01*
X547559Y-61574D01*
X542319D01*
G01X568989Y-52824D02*
X567679Y-51948D01*
X566151Y-51365D01*
X564404D01*
X562439Y-52240D01*
X560911Y-53698D01*
X559819Y-55449D01*
X558946Y-58365D01*
X558727Y-60990D01*
X559164Y-63615D01*
X559819Y-65365D01*
X561129Y-67115D01*
X562658Y-68282D01*
X564186Y-68865D01*
X565714D01*
X567243Y-68282D01*
X568553Y-67407D01*
X569645Y-66241D01*
G01X583432Y-59532D02*
X584306Y-58657D01*
X584961Y-57199D01*
X585398Y-55156D01*
X584961Y-53407D01*
X584088Y-52240D01*
X582559Y-51365D01*
X576664D01*
Y-68865D01*
X583869D01*
X585398Y-67699D01*
X586271Y-65948D01*
X586708Y-63907D01*
X586271Y-61865D01*
X584961Y-60115D01*
X583432Y-59532D01*
X576664D01*
G01X592636Y-74698D02*
X605736D01*
G01X611664Y-68865D02*
Y-51365D01*
X621708Y-68865D01*
Y-51365D01*
G01X634186Y-68865D02*
X632439Y-68573D01*
X630911Y-67407D01*
X629601Y-65657D01*
X628727Y-63615D01*
X628291Y-61282D01*
Y-58948D01*
X628727Y-56615D01*
X629601Y-54573D01*
X630911Y-52824D01*
X632439Y-51657D01*
X634186Y-51365D01*
X635932Y-51657D01*
X637461Y-52824D01*
X638771Y-54573D01*
X639645Y-56615D01*
X640081Y-58948D01*
Y-61282D01*
X639645Y-63615D01*
X638771Y-65657D01*
X637461Y-67407D01*
X635932Y-68573D01*
X634186Y-68865D01*
G01X555436Y-113865D02*
Y-96365D01*
X552816Y-99865D01*
G01Y-113865D02*
X558056D01*
G01X568133Y-110365D02*
X569442Y-112407D01*
X571189Y-113573D01*
X573154Y-113865D01*
X574901Y-113573D01*
X576648Y-112115D01*
X577739Y-110365D01*
X577958Y-108615D01*
X577521Y-106574D01*
X575993Y-105115D01*
X574464Y-104532D01*
X572499D01*
G01X574464D02*
X575774Y-103657D01*
X576866Y-102199D01*
X577303Y-100449D01*
X576866Y-98698D01*
X575774Y-97240D01*
X573809Y-96365D01*
X571844Y-96657D01*
X569879Y-97824D01*
G01X590436Y-113865D02*
Y-96365D01*
X587816Y-99865D01*
G01Y-113865D02*
X593056D01*
G01X603133Y-110365D02*
X604442Y-112407D01*
X606189Y-113573D01*
X608154Y-113865D01*
X609901Y-113573D01*
X611648Y-112115D01*
X612739Y-110365D01*
X612958Y-108615D01*
X612521Y-106574D01*
X610993Y-105115D01*
X609464Y-104532D01*
X607499D01*
G01X609464D02*
X610774Y-103657D01*
X611866Y-102199D01*
X612303Y-100449D01*
X611866Y-98698D01*
X610774Y-97240D01*
X608809Y-96365D01*
X606844Y-96657D01*
X604879Y-97824D01*
G01X625436Y-96365D02*
X623689Y-96948D01*
X622379Y-98407D01*
X621506Y-100156D01*
X620851Y-102490D01*
X620633Y-105115D01*
X620851Y-107740D01*
X621506Y-110074D01*
X622379Y-111824D01*
X623689Y-113282D01*
X625436Y-113865D01*
X627182Y-113282D01*
X628493Y-111824D01*
X629366Y-110074D01*
X630021Y-107740D01*
X630239Y-105115D01*
X630021Y-102490D01*
X629366Y-100156D01*
X628493Y-98407D01*
X627182Y-96948D01*
X625436Y-96365D01*
G01X685027Y-51365D02*
X690486Y-68865D01*
X695945Y-51365D01*
G01X712353Y-68865D02*
X703619D01*
Y-51365D01*
X712353D01*
G01X708859Y-59823D02*
X703619D01*
G01X721119Y-68865D02*
Y-51365D01*
X726578D01*
X728324Y-52240D01*
X729416Y-53407D01*
X729853Y-55740D01*
X729416Y-58074D01*
X728106Y-59532D01*
X726578Y-60407D01*
X721119D01*
G01X726578D02*
X729853Y-68865D01*
G01X742986Y-69448D02*
X742549Y-69157D01*
Y-68573D01*
X742986Y-68282D01*
X743423Y-68573D01*
Y-69157D01*
X742986Y-69448D01*
G01X707986Y-113865D02*
Y-96365D01*
X705366Y-99865D01*
G01Y-113865D02*
X710606D01*
G01X727232Y-104532D02*
X728106Y-103657D01*
X728761Y-102199D01*
X729198Y-100156D01*
X728761Y-98407D01*
X727888Y-97240D01*
X726359Y-96365D01*
X720464D01*
Y-113865D01*
X727669D01*
X729198Y-112699D01*
X730071Y-110948D01*
X730508Y-108907D01*
X730071Y-106865D01*
X728761Y-105115D01*
X727232Y-104532D01*
X720464D01*
G01X897303Y-96365D02*
Y-113865D01*
X888569D01*
G01X875873D02*
X875436Y-110074D01*
X874781Y-106865D01*
X873908Y-103948D01*
X872816Y-100740D01*
X871069Y-96365D01*
X879803D01*
G01X863395D02*
X857936Y-113865D01*
X852477Y-96365D01*
G01X835633Y-97824D02*
X836943Y-96948D01*
X838471Y-96365D01*
X840218D01*
X842183Y-97240D01*
X843711Y-98698D01*
X844803Y-100449D01*
X845676Y-103365D01*
X845895Y-105990D01*
X845458Y-108615D01*
X844803Y-110365D01*
X843493Y-112115D01*
X841964Y-113282D01*
X840436Y-113865D01*
X838908D01*
X837379Y-113282D01*
X836069Y-112407D01*
X834977Y-111241D01*
G01X818133Y-97824D02*
X819443Y-96948D01*
X820971Y-96365D01*
X822718D01*
X824683Y-97240D01*
X826211Y-98698D01*
X827303Y-100449D01*
X828176Y-103365D01*
X828395Y-105990D01*
X827958Y-108615D01*
X827303Y-110365D01*
X825993Y-112115D01*
X824464Y-113282D01*
X822936Y-113865D01*
X821408D01*
X819879Y-113282D01*
X818569Y-112407D01*
X817477Y-111241D01*
G01X818569Y-51365D02*
Y-68865D01*
X827303D01*
G01X844366D02*
Y-57199D01*
G01Y-59240D02*
X843493Y-58074D01*
X842182Y-57490D01*
X840654Y-57199D01*
X839126Y-57782D01*
X837816Y-58948D01*
X836942Y-60698D01*
X836506Y-63032D01*
X836942Y-65365D01*
X837816Y-67115D01*
X839126Y-68282D01*
X840654Y-68865D01*
X842182Y-68573D01*
X843493Y-67699D01*
X844366Y-66532D01*
G01X853351Y-74115D02*
X854661Y-74698D01*
X856408Y-74115D01*
X857499Y-72949D01*
X858373Y-71490D01*
X859682Y-66824D01*
X862521Y-57199D01*
G01X855534D02*
X859682Y-66824D01*
G01X872161Y-60990D02*
X879148D01*
X878493Y-58948D01*
X877401Y-57782D01*
X875873Y-57199D01*
X874344Y-57490D01*
X873034Y-58365D01*
X872161Y-60407D01*
X871724Y-62157D01*
Y-63907D01*
X872161Y-65657D01*
X873253Y-67407D01*
X874563Y-68573D01*
X876091Y-68865D01*
X877619Y-68282D01*
X879148Y-66532D01*
G01X889879Y-68865D02*
Y-57199D01*
G01Y-59532D02*
X890971Y-58365D01*
X892063Y-57490D01*
X893591Y-57199D01*
X894682Y-57490D01*
X895993Y-58365D01*
G01X943619Y-110365D02*
X944711Y-112115D01*
X946021Y-113282D01*
X947549Y-113865D01*
X949296Y-113282D01*
X950606Y-112115D01*
X951916Y-110365D01*
X952353Y-108032D01*
Y-96365D01*
G01X965486Y-113865D02*
X963739Y-113573D01*
X962211Y-112407D01*
X960901Y-110657D01*
X960027Y-108615D01*
X959591Y-106282D01*
Y-103948D01*
X960027Y-101615D01*
X960901Y-99573D01*
X962211Y-97824D01*
X963739Y-96657D01*
X965486Y-96365D01*
X967232Y-96657D01*
X968761Y-97824D01*
X970071Y-99573D01*
X970945Y-101615D01*
X971381Y-103948D01*
Y-106282D01*
X970945Y-108615D01*
X970071Y-110657D01*
X968761Y-112407D01*
X967232Y-113573D01*
X965486Y-113865D01*
G01X978401Y-111532D02*
X980148Y-112990D01*
X982113Y-113865D01*
X983859D01*
X985606Y-112990D01*
X986916Y-111532D01*
X987571Y-109490D01*
X987134Y-107449D01*
X986043Y-105698D01*
X984078Y-104532D01*
X981458Y-103948D01*
X979929Y-102782D01*
X979274Y-100740D01*
X979711Y-98698D01*
X980803Y-97240D01*
X982331Y-96365D01*
X983859D01*
X985388Y-96948D01*
X986698Y-98407D01*
G01X1004853Y-113865D02*
X996119D01*
Y-96365D01*
X1004853D01*
G01X1001359Y-104823D02*
X996119D01*
G01X1013619Y-113865D02*
Y-96365D01*
X1018859D01*
X1020606Y-97240D01*
X1021916Y-99282D01*
X1022353Y-101615D01*
X1021916Y-103948D01*
X1020824Y-105698D01*
X1018859Y-106574D01*
X1013619D01*
G01X1030901Y-113865D02*
Y-96365D01*
G01X1040071D02*
Y-113865D01*
G01Y-105115D02*
X1030901D01*
G01X1066119Y-96365D02*
Y-113865D01*
X1074853D01*
G01X1082527D02*
X1087986Y-96365D01*
X1093445Y-113865D01*
G01X1091479Y-107740D02*
X1084492D01*
G01X1100683Y-96365D02*
Y-108907D01*
X1101556Y-111532D01*
X1103303Y-113282D01*
X1105486Y-113865D01*
X1107669Y-113282D01*
X1109416Y-111532D01*
X1110289Y-108907D01*
Y-96365D01*
G01X960683Y-68865D02*
Y-51365D01*
X965049D01*
X966796Y-52240D01*
X968106Y-53407D01*
X969198Y-55156D01*
X970071Y-57199D01*
X970289Y-60115D01*
X970071Y-63032D01*
X969198Y-65074D01*
X968106Y-66824D01*
X966796Y-67990D01*
X965049Y-68865D01*
X960683D01*
G01X979711Y-60990D02*
X986698D01*
X986043Y-58948D01*
X984951Y-57782D01*
X983423Y-57199D01*
X981894Y-57490D01*
X980584Y-58365D01*
X979711Y-60407D01*
X979274Y-62157D01*
Y-63907D01*
X979711Y-65657D01*
X980803Y-67407D01*
X982113Y-68573D01*
X983641Y-68865D01*
X985169Y-68282D01*
X986698Y-66532D01*
G01X997211Y-66824D02*
X998303Y-67990D01*
X999831Y-68865D01*
X1001141D01*
X1002451Y-68282D01*
X1003324Y-67407D01*
X1003761Y-66241D01*
X1003543Y-64490D01*
X1002669Y-63615D01*
X998739Y-61865D01*
X997866Y-59823D01*
X998303Y-58365D01*
X999176Y-57490D01*
X1000486Y-57199D01*
X1001796Y-57490D01*
X1003106Y-58365D01*
G01X1017986Y-57199D02*
Y-68865D01*
G01Y-52532D02*
X1017549Y-52240D01*
Y-51657D01*
X1017986Y-51365D01*
X1018423Y-51657D01*
Y-52240D01*
X1017986Y-52532D01*
G01X1032429Y-73240D02*
X1033958Y-74407D01*
X1035704Y-74698D01*
X1037232Y-74407D01*
X1038543Y-72949D01*
X1039416Y-70907D01*
Y-57199D01*
G01Y-59532D02*
X1038543Y-58365D01*
X1037232Y-57490D01*
X1035704Y-57199D01*
X1033958Y-57782D01*
X1032866Y-58948D01*
X1031992Y-60990D01*
X1031556Y-63032D01*
X1031774Y-64782D01*
X1032648Y-66824D01*
X1033958Y-68282D01*
X1035704Y-68865D01*
X1037014Y-68573D01*
X1038543Y-67407D01*
X1039416Y-66241D01*
G01X1049274Y-68865D02*
Y-57199D01*
G01Y-60115D02*
X1050148Y-58657D01*
X1051458Y-57490D01*
X1053204Y-57199D01*
X1054732Y-57490D01*
X1056043Y-58657D01*
X1056698Y-60698D01*
Y-68865D01*
G01X1067211Y-60990D02*
X1074198D01*
X1073543Y-58948D01*
X1072451Y-57782D01*
X1070923Y-57199D01*
X1069394Y-57490D01*
X1068084Y-58365D01*
X1067211Y-60407D01*
X1066774Y-62157D01*
Y-63907D01*
X1067211Y-65657D01*
X1068303Y-67407D01*
X1069613Y-68573D01*
X1071141Y-68865D01*
X1072669Y-68282D01*
X1074198Y-66532D01*
G01X1084929Y-68865D02*
Y-57199D01*
G01Y-59532D02*
X1086021Y-58365D01*
X1087113Y-57490D01*
X1088641Y-57199D01*
X1089732Y-57490D01*
X1091043Y-58365D01*
G01X1131686Y-113865D02*
Y-96365D01*
X1129066Y-99865D01*
G01Y-113865D02*
X1134306D01*
G01X1149186D02*
Y-96365D01*
X1146566Y-99865D01*
G01Y-113865D02*
X1151806D01*
G01X1162756Y-114448D02*
X1170616Y-96365D01*
G01X1184186Y-113865D02*
Y-96365D01*
X1181566Y-99865D01*
G01Y-113865D02*
X1186806D01*
G01X1196883Y-110365D02*
X1198192Y-112407D01*
X1199939Y-113573D01*
X1201904Y-113865D01*
X1203651Y-113573D01*
X1205398Y-112115D01*
X1206489Y-110365D01*
X1206708Y-108615D01*
X1206271Y-106574D01*
X1204743Y-105115D01*
X1203214Y-104532D01*
X1201249D01*
G01X1203214D02*
X1204524Y-103657D01*
X1205616Y-102199D01*
X1206053Y-100449D01*
X1205616Y-98698D01*
X1204524Y-97240D01*
X1202559Y-96365D01*
X1200594Y-96657D01*
X1198629Y-97824D01*
G01X1215256Y-114448D02*
X1223116Y-96365D01*
G01X1232538Y-99282D02*
X1233848Y-97532D01*
X1235376Y-96657D01*
X1237123Y-96365D01*
X1239306Y-96948D01*
X1240834Y-98407D01*
X1241271Y-100156D01*
X1241053Y-101907D01*
X1240179Y-103365D01*
X1235813Y-106282D01*
X1233848Y-108323D01*
X1232538Y-111241D01*
X1232101Y-113865D01*
X1241271D01*
G01X1254186Y-96365D02*
X1252439Y-96948D01*
X1251129Y-98407D01*
X1250256Y-100156D01*
X1249601Y-102490D01*
X1249383Y-105115D01*
X1249601Y-107740D01*
X1250256Y-110074D01*
X1251129Y-111824D01*
X1252439Y-113282D01*
X1254186Y-113865D01*
X1255932Y-113282D01*
X1257243Y-111824D01*
X1258116Y-110074D01*
X1258771Y-107740D01*
X1258989Y-105115D01*
X1258771Y-102490D01*
X1258116Y-100156D01*
X1257243Y-98407D01*
X1255932Y-96948D01*
X1254186Y-96365D01*
G01X1271686Y-113865D02*
Y-96365D01*
X1269066Y-99865D01*
G01Y-113865D02*
X1274306D01*
G01X1291806D02*
Y-96365D01*
X1283727Y-108907D01*
X1294645D01*
G01X1179383Y-68865D02*
Y-51365D01*
X1183749D01*
X1185496Y-52240D01*
X1186806Y-53407D01*
X1187898Y-55156D01*
X1188771Y-57199D01*
X1188989Y-60115D01*
X1188771Y-63032D01*
X1187898Y-65074D01*
X1186806Y-66824D01*
X1185496Y-67990D01*
X1183749Y-68865D01*
X1179383D01*
G01X1205616D02*
Y-57199D01*
G01Y-59240D02*
X1204743Y-58074D01*
X1203432Y-57490D01*
X1201904Y-57199D01*
X1200376Y-57782D01*
X1199066Y-58948D01*
X1198192Y-60698D01*
X1197756Y-63032D01*
X1198192Y-65365D01*
X1199066Y-67115D01*
X1200376Y-68282D01*
X1201904Y-68865D01*
X1203432Y-68573D01*
X1204743Y-67699D01*
X1205616Y-66532D01*
G01X1219186Y-51365D02*
Y-68865D01*
G01X1216129Y-57199D02*
X1222243D01*
G01X1233411Y-60990D02*
X1240398D01*
X1239743Y-58948D01*
X1238651Y-57782D01*
X1237123Y-57199D01*
X1235594Y-57490D01*
X1234284Y-58365D01*
X1233411Y-60407D01*
X1232974Y-62157D01*
Y-63907D01*
X1233411Y-65657D01*
X1234503Y-67407D01*
X1235813Y-68573D01*
X1237341Y-68865D01*
X1238869Y-68282D01*
X1240398Y-66532D01*
M02*
